FILE_TYPE = MACRO_DRAWING;
SET COLOR_WIRE YELLOW;
SET COLOR_PROP ORANGE;
SET COLOR_DOT WHITE;
SET COLOR_ARC YELLOW;
SET COLOR_BODY GREEN;
SET COLOR_NOTE PURPLE;
SET PROP_DISPLAY VALUE;
SET PAGE_NUMBER P96;
FORCEADD OFFPAGE..5
(-8325 1625);
FORCEPROP 2 LAST $XR0 21 
J 0
(-8549 1625);
DISPLAY 0.638298 (-8549 1625);
PAINT MONO (-8549 1625);
FORCEPROP 2 LAST CDS_LIB mstr_standard
J 0
(-8325 1625);
DISPLAY 0.808511 (-8325 1625);
DISPLAY INVISIBLE (-8325 1625);
FORCEPROP 1 LAST OFFPAGE TRUE
J 0
(-8000 1500);
DISPLAY 0.872340 (-8000 1500);
PAINT GREEN (-8000 1500);
DISPLAY INVISIBLE (-8000 1500);
FORCEPROP 1 LAST COMMENT_BODY TRUE
J 0
(-8225 1550);
DISPLAY 0.872340 (-8225 1550);
PAINT GREEN (-8225 1550);
DISPLAY INVISIBLE (-8225 1550);
FORCEPROP 2 LAST PATH I1
J 0
(-8275 1700);
DISPLAY 1.021277 (-8275 1700);
DISPLAY INVISIBLE (-8275 1700);
FORCEADD OFFPAGE..6
(-8325 3275);
FORCEPROP 2 LAST $XR0 21 
J 0
(-8574 3275);
DISPLAY 0.638298 (-8574 3275);
PAINT MONO (-8574 3275);
FORCEPROP 2 LAST CDS_LIB mstr_standard
J 0
(-8325 3275);
DISPLAY 0.723404 (-8325 3275);
PAINT MONO (-8325 3275);
DISPLAY INVISIBLE (-8325 3275);
FORCEPROP 1 LAST OFFPAGE TRUE
J 0
(-8000 3150);
DISPLAY 0.872340 (-8000 3150);
PAINT GREEN (-8000 3150);
DISPLAY INVISIBLE (-8000 3150);
FORCEPROP 1 LAST COMMENT_BODY TRUE
J 0
(-8225 3200);
DISPLAY 0.872340 (-8225 3200);
PAINT GREEN (-8225 3200);
DISPLAY INVISIBLE (-8225 3200);
FORCEPROP 2 LAST PATH I10
J 0
(-8275 3350);
DISPLAY 1.021277 (-8275 3350);
DISPLAY INVISIBLE (-8275 3350);
FORCEADD TAP..1
(-6025 3925);
FORCEPROP 3 LASTPIN (-6075 3925) SIG_NAME M_L_CPU0_SA_DQ<8>
J 0
(-6065 3935);
DISPLAY 0.659574 (-6065 3935);
PAINT MONO (-6065 3935);
DISPLAY INVISIBLE (-6065 3935);
FORCEPROP 1 LASTPIN (-6075 3925) BN 8
J 0
(-6087 3933);
DISPLAY 0.489362 (-6087 3933);
PAINT GREEN (-6087 3933);
FORCEPROP 2 LAST CDS_LIB mstr_standard
J 0
(-6025 3925);
DISPLAY 0.723404 (-6025 3925);
PAINT MONO (-6025 3925);
DISPLAY INVISIBLE (-6025 3925);
FORCEPROP 1 LAST BODY_TYPE PLUMBING
J 0
(-6025 3975);
DISPLAY 0.872340 (-6025 3975);
PAINT GREEN (-6025 3975);
DISPLAY INVISIBLE (-6025 3975);
FORCEPROP 1 LAST HDL_TAP TRUE
J 0
(-5700 3800);
DISPLAY 0.872340 (-5700 3800);
DISPLAY INVISIBLE (-5700 3800);
FORCEPROP 1 LAST PATH I100
J 0
(-6027 3925);
DISPLAY 0.872340 (-6027 3925);
PAINT GREEN (-6027 3925);
DISPLAY INVISIBLE (-6027 3925);
FORCEADD TAP..1
(-6025 3975);
FORCEPROP 3 LASTPIN (-6075 3975) SIG_NAME M_L_CPU0_SA_DQ<9>
J 0
(-6065 3985);
DISPLAY 0.659574 (-6065 3985);
PAINT MONO (-6065 3985);
DISPLAY INVISIBLE (-6065 3985);
FORCEPROP 1 LASTPIN (-6075 3975) BN 9
J 0
(-6087 3983);
DISPLAY 0.489362 (-6087 3983);
PAINT GREEN (-6087 3983);
FORCEPROP 2 LAST CDS_LIB mstr_standard
J 0
(-6025 3975);
DISPLAY 0.723404 (-6025 3975);
PAINT MONO (-6025 3975);
DISPLAY INVISIBLE (-6025 3975);
FORCEPROP 1 LAST BODY_TYPE PLUMBING
J 0
(-6025 4025);
DISPLAY 0.872340 (-6025 4025);
PAINT GREEN (-6025 4025);
DISPLAY INVISIBLE (-6025 4025);
FORCEPROP 1 LAST HDL_TAP TRUE
J 0
(-5700 3850);
DISPLAY 0.872340 (-5700 3850);
DISPLAY INVISIBLE (-5700 3850);
FORCEPROP 1 LAST PATH I101
J 0
(-6027 3975);
DISPLAY 0.872340 (-6027 3975);
PAINT GREEN (-6027 3975);
DISPLAY INVISIBLE (-6027 3975);
FORCEADD TAP..1
(-6025 4025);
FORCEPROP 3 LASTPIN (-6075 4025) SIG_NAME M_L_CPU0_SA_DQ<10>
J 0
(-6065 4035);
DISPLAY 0.659574 (-6065 4035);
PAINT MONO (-6065 4035);
DISPLAY INVISIBLE (-6065 4035);
FORCEPROP 1 LASTPIN (-6075 4025) BN 10
J 0
(-6087 4033);
DISPLAY 0.489362 (-6087 4033);
PAINT GREEN (-6087 4033);
FORCEPROP 2 LAST CDS_LIB mstr_standard
J 0
(-6025 4025);
DISPLAY 0.723404 (-6025 4025);
PAINT MONO (-6025 4025);
DISPLAY INVISIBLE (-6025 4025);
FORCEPROP 1 LAST BODY_TYPE PLUMBING
J 0
(-6025 4075);
DISPLAY 0.872340 (-6025 4075);
PAINT GREEN (-6025 4075);
DISPLAY INVISIBLE (-6025 4075);
FORCEPROP 1 LAST HDL_TAP TRUE
J 0
(-5700 3900);
DISPLAY 0.872340 (-5700 3900);
DISPLAY INVISIBLE (-5700 3900);
FORCEPROP 1 LAST PATH I102
J 0
(-6027 4025);
DISPLAY 0.872340 (-6027 4025);
PAINT GREEN (-6027 4025);
DISPLAY INVISIBLE (-6027 4025);
FORCEADD TAP..1
(-6025 4125);
FORCEPROP 3 LASTPIN (-6075 4125) SIG_NAME M_L_CPU0_SA_DQ<12>
J 0
(-6065 4135);
DISPLAY 0.659574 (-6065 4135);
PAINT MONO (-6065 4135);
DISPLAY INVISIBLE (-6065 4135);
FORCEPROP 1 LASTPIN (-6075 4125) BN 12
J 0
(-6087 4133);
DISPLAY 0.489362 (-6087 4133);
PAINT GREEN (-6087 4133);
FORCEPROP 2 LAST CDS_LIB mstr_standard
J 0
(-6025 4125);
DISPLAY 0.723404 (-6025 4125);
PAINT MONO (-6025 4125);
DISPLAY INVISIBLE (-6025 4125);
FORCEPROP 1 LAST BODY_TYPE PLUMBING
J 0
(-6025 4175);
DISPLAY 0.872340 (-6025 4175);
PAINT GREEN (-6025 4175);
DISPLAY INVISIBLE (-6025 4175);
FORCEPROP 1 LAST HDL_TAP TRUE
J 0
(-5700 4000);
DISPLAY 0.872340 (-5700 4000);
DISPLAY INVISIBLE (-5700 4000);
FORCEPROP 1 LAST PATH I103
J 0
(-6027 4125);
DISPLAY 0.872340 (-6027 4125);
PAINT GREEN (-6027 4125);
DISPLAY INVISIBLE (-6027 4125);
FORCEADD TAP..1
(-6025 4075);
FORCEPROP 3 LASTPIN (-6075 4075) SIG_NAME M_L_CPU0_SA_DQ<11>
J 0
(-6065 4085);
DISPLAY 0.659574 (-6065 4085);
PAINT MONO (-6065 4085);
DISPLAY INVISIBLE (-6065 4085);
FORCEPROP 1 LASTPIN (-6075 4075) BN 11
J 0
(-6087 4083);
DISPLAY 0.489362 (-6087 4083);
PAINT GREEN (-6087 4083);
FORCEPROP 2 LAST CDS_LIB mstr_standard
J 0
(-6025 4075);
DISPLAY 0.723404 (-6025 4075);
PAINT MONO (-6025 4075);
DISPLAY INVISIBLE (-6025 4075);
FORCEPROP 1 LAST BODY_TYPE PLUMBING
J 0
(-6025 4125);
DISPLAY 0.872340 (-6025 4125);
PAINT GREEN (-6025 4125);
DISPLAY INVISIBLE (-6025 4125);
FORCEPROP 1 LAST HDL_TAP TRUE
J 0
(-5700 3950);
DISPLAY 0.872340 (-5700 3950);
DISPLAY INVISIBLE (-5700 3950);
FORCEPROP 1 LAST PATH I104
J 0
(-6027 4075);
DISPLAY 0.872340 (-6027 4075);
PAINT GREEN (-6027 4075);
DISPLAY INVISIBLE (-6027 4075);
FORCEADD TAP..1
(-6025 4175);
FORCEPROP 3 LASTPIN (-6075 4175) SIG_NAME M_L_CPU0_SA_DQ<13>
J 0
(-6065 4185);
DISPLAY 0.659574 (-6065 4185);
PAINT MONO (-6065 4185);
DISPLAY INVISIBLE (-6065 4185);
FORCEPROP 1 LASTPIN (-6075 4175) BN 13
J 0
(-6087 4183);
DISPLAY 0.489362 (-6087 4183);
PAINT GREEN (-6087 4183);
FORCEPROP 2 LAST CDS_LIB mstr_standard
J 0
(-6025 4175);
DISPLAY 0.723404 (-6025 4175);
PAINT MONO (-6025 4175);
DISPLAY INVISIBLE (-6025 4175);
FORCEPROP 1 LAST BODY_TYPE PLUMBING
J 0
(-6025 4225);
DISPLAY 0.872340 (-6025 4225);
PAINT GREEN (-6025 4225);
DISPLAY INVISIBLE (-6025 4225);
FORCEPROP 1 LAST HDL_TAP TRUE
J 0
(-5700 4050);
DISPLAY 0.872340 (-5700 4050);
DISPLAY INVISIBLE (-5700 4050);
FORCEPROP 1 LAST PATH I105
J 0
(-6027 4175);
DISPLAY 0.872340 (-6027 4175);
PAINT GREEN (-6027 4175);
DISPLAY INVISIBLE (-6027 4175);
FORCEADD TAP..1
(-6025 4225);
FORCEPROP 3 LASTPIN (-6075 4225) SIG_NAME M_L_CPU0_SA_DQ<14>
J 0
(-6065 4235);
DISPLAY 0.659574 (-6065 4235);
PAINT MONO (-6065 4235);
DISPLAY INVISIBLE (-6065 4235);
FORCEPROP 1 LASTPIN (-6075 4225) BN 14
J 0
(-6087 4233);
DISPLAY 0.489362 (-6087 4233);
PAINT GREEN (-6087 4233);
FORCEPROP 2 LAST CDS_LIB mstr_standard
J 0
(-6025 4225);
DISPLAY 0.723404 (-6025 4225);
PAINT MONO (-6025 4225);
DISPLAY INVISIBLE (-6025 4225);
FORCEPROP 1 LAST BODY_TYPE PLUMBING
J 0
(-6025 4275);
DISPLAY 0.872340 (-6025 4275);
PAINT GREEN (-6025 4275);
DISPLAY INVISIBLE (-6025 4275);
FORCEPROP 1 LAST HDL_TAP TRUE
J 0
(-5700 4100);
DISPLAY 0.872340 (-5700 4100);
DISPLAY INVISIBLE (-5700 4100);
FORCEPROP 1 LAST PATH I106
J 0
(-6027 4225);
DISPLAY 0.872340 (-6027 4225);
PAINT GREEN (-6027 4225);
DISPLAY INVISIBLE (-6027 4225);
FORCEADD TAP..1
(-6025 4275);
FORCEPROP 3 LASTPIN (-6075 4275) SIG_NAME M_L_CPU0_SA_DQ<15>
J 0
(-6065 4285);
DISPLAY 0.659574 (-6065 4285);
PAINT MONO (-6065 4285);
DISPLAY INVISIBLE (-6065 4285);
FORCEPROP 1 LASTPIN (-6075 4275) BN 15
J 0
(-6087 4283);
DISPLAY 0.489362 (-6087 4283);
PAINT GREEN (-6087 4283);
FORCEPROP 2 LAST CDS_LIB mstr_standard
J 0
(-6025 4275);
DISPLAY 0.723404 (-6025 4275);
PAINT MONO (-6025 4275);
DISPLAY INVISIBLE (-6025 4275);
FORCEPROP 1 LAST BODY_TYPE PLUMBING
J 0
(-6025 4325);
DISPLAY 0.872340 (-6025 4325);
PAINT GREEN (-6025 4325);
DISPLAY INVISIBLE (-6025 4325);
FORCEPROP 1 LAST HDL_TAP TRUE
J 0
(-5700 4150);
DISPLAY 0.872340 (-5700 4150);
DISPLAY INVISIBLE (-5700 4150);
FORCEPROP 1 LAST PATH I107
J 0
(-6027 4275);
DISPLAY 0.872340 (-6027 4275);
PAINT GREEN (-6027 4275);
DISPLAY INVISIBLE (-6027 4275);
FORCEADD TAP..1
(-6025 4325);
FORCEPROP 3 LASTPIN (-6075 4325) SIG_NAME M_L_CPU0_SA_DQ<16>
J 0
(-6065 4335);
DISPLAY 0.659574 (-6065 4335);
PAINT MONO (-6065 4335);
DISPLAY INVISIBLE (-6065 4335);
FORCEPROP 1 LASTPIN (-6075 4325) BN 16
J 0
(-6087 4333);
DISPLAY 0.489362 (-6087 4333);
PAINT GREEN (-6087 4333);
FORCEPROP 2 LAST CDS_LIB mstr_standard
J 0
(-6025 4325);
DISPLAY 0.723404 (-6025 4325);
PAINT MONO (-6025 4325);
DISPLAY INVISIBLE (-6025 4325);
FORCEPROP 1 LAST BODY_TYPE PLUMBING
J 0
(-6025 4375);
DISPLAY 0.872340 (-6025 4375);
PAINT GREEN (-6025 4375);
DISPLAY INVISIBLE (-6025 4375);
FORCEPROP 1 LAST HDL_TAP TRUE
J 0
(-5700 4200);
DISPLAY 0.872340 (-5700 4200);
DISPLAY INVISIBLE (-5700 4200);
FORCEPROP 1 LAST PATH I108
J 0
(-6027 4325);
DISPLAY 0.872340 (-6027 4325);
PAINT GREEN (-6027 4325);
DISPLAY INVISIBLE (-6027 4325);
FORCEADD TAP..1
(-6025 4425);
FORCEPROP 3 LASTPIN (-6075 4425) SIG_NAME M_L_CPU0_SA_DQ<18>
J 0
(-6065 4435);
DISPLAY 0.659574 (-6065 4435);
PAINT MONO (-6065 4435);
DISPLAY INVISIBLE (-6065 4435);
FORCEPROP 1 LASTPIN (-6075 4425) BN 18
J 0
(-6087 4433);
DISPLAY 0.489362 (-6087 4433);
PAINT GREEN (-6087 4433);
FORCEPROP 2 LAST CDS_LIB mstr_standard
J 0
(-6025 4425);
DISPLAY 0.723404 (-6025 4425);
PAINT MONO (-6025 4425);
DISPLAY INVISIBLE (-6025 4425);
FORCEPROP 1 LAST BODY_TYPE PLUMBING
J 0
(-6025 4475);
DISPLAY 0.872340 (-6025 4475);
PAINT GREEN (-6025 4475);
DISPLAY INVISIBLE (-6025 4475);
FORCEPROP 1 LAST HDL_TAP TRUE
J 0
(-5700 4300);
DISPLAY 0.872340 (-5700 4300);
DISPLAY INVISIBLE (-5700 4300);
FORCEPROP 1 LAST PATH I109
J 0
(-6027 4425);
DISPLAY 0.872340 (-6027 4425);
PAINT GREEN (-6027 4425);
DISPLAY INVISIBLE (-6027 4425);
FORCEADD OFFPAGE..1
(-8325 3825);
FORCEPROP 2 LAST $XR0 21 
J 0
(-8546 3825);
DISPLAY 0.638298 (-8546 3825);
PAINT MONO (-8546 3825);
FORCEPROP 2 LAST CDS_LIB mstr_standard
J 0
(-8325 3825);
DISPLAY 0.723404 (-8325 3825);
PAINT MONO (-8325 3825);
DISPLAY INVISIBLE (-8325 3825);
FORCEPROP 1 LAST OFFPAGE TRUE
J 0
(-8000 3700);
DISPLAY 0.872340 (-8000 3700);
PAINT GREEN (-8000 3700);
DISPLAY INVISIBLE (-8000 3700);
FORCEPROP 1 LAST COMMENT_BODY TRUE
J 0
(-8200 3725);
DISPLAY 0.872340 (-8200 3725);
PAINT GREEN (-8200 3725);
DISPLAY INVISIBLE (-8200 3725);
FORCEPROP 2 LAST PATH I11
J 0
(-8275 3900);
DISPLAY 1.021277 (-8275 3900);
DISPLAY INVISIBLE (-8275 3900);
FORCEADD TAP..1
(-6025 4375);
FORCEPROP 3 LASTPIN (-6075 4375) SIG_NAME M_L_CPU0_SA_DQ<17>
J 0
(-6065 4385);
DISPLAY 0.659574 (-6065 4385);
PAINT MONO (-6065 4385);
DISPLAY INVISIBLE (-6065 4385);
FORCEPROP 1 LASTPIN (-6075 4375) BN 17
J 0
(-6087 4383);
DISPLAY 0.489362 (-6087 4383);
PAINT GREEN (-6087 4383);
FORCEPROP 2 LAST CDS_LIB mstr_standard
J 0
(-6025 4375);
DISPLAY 0.723404 (-6025 4375);
PAINT MONO (-6025 4375);
DISPLAY INVISIBLE (-6025 4375);
FORCEPROP 1 LAST BODY_TYPE PLUMBING
J 0
(-6025 4425);
DISPLAY 0.872340 (-6025 4425);
PAINT GREEN (-6025 4425);
DISPLAY INVISIBLE (-6025 4425);
FORCEPROP 1 LAST HDL_TAP TRUE
J 0
(-5700 4250);
DISPLAY 0.872340 (-5700 4250);
DISPLAY INVISIBLE (-5700 4250);
FORCEPROP 1 LAST PATH I110
J 0
(-6027 4375);
DISPLAY 0.872340 (-6027 4375);
PAINT GREEN (-6027 4375);
DISPLAY INVISIBLE (-6027 4375);
FORCEADD TAP..1
(-6025 4475);
FORCEPROP 3 LASTPIN (-6075 4475) SIG_NAME M_L_CPU0_SA_DQ<19>
J 0
(-6065 4485);
DISPLAY 0.659574 (-6065 4485);
PAINT MONO (-6065 4485);
DISPLAY INVISIBLE (-6065 4485);
FORCEPROP 1 LASTPIN (-6075 4475) BN 19
J 0
(-6087 4483);
DISPLAY 0.489362 (-6087 4483);
PAINT GREEN (-6087 4483);
FORCEPROP 2 LAST CDS_LIB mstr_standard
J 0
(-6025 4475);
DISPLAY 0.723404 (-6025 4475);
PAINT MONO (-6025 4475);
DISPLAY INVISIBLE (-6025 4475);
FORCEPROP 1 LAST BODY_TYPE PLUMBING
J 0
(-6025 4525);
DISPLAY 0.872340 (-6025 4525);
PAINT GREEN (-6025 4525);
DISPLAY INVISIBLE (-6025 4525);
FORCEPROP 1 LAST HDL_TAP TRUE
J 0
(-5700 4350);
DISPLAY 0.872340 (-5700 4350);
DISPLAY INVISIBLE (-5700 4350);
FORCEPROP 1 LAST PATH I111
J 0
(-6027 4475);
DISPLAY 0.872340 (-6027 4475);
PAINT GREEN (-6027 4475);
DISPLAY INVISIBLE (-6027 4475);
FORCEADD TAP..1
(-6025 4525);
FORCEPROP 3 LASTPIN (-6075 4525) SIG_NAME M_L_CPU0_SA_DQ<20>
J 0
(-6065 4535);
DISPLAY 0.659574 (-6065 4535);
PAINT MONO (-6065 4535);
DISPLAY INVISIBLE (-6065 4535);
FORCEPROP 1 LASTPIN (-6075 4525) BN 20
J 0
(-6087 4533);
DISPLAY 0.489362 (-6087 4533);
PAINT GREEN (-6087 4533);
FORCEPROP 2 LAST CDS_LIB mstr_standard
J 0
(-6025 4525);
DISPLAY 0.723404 (-6025 4525);
PAINT MONO (-6025 4525);
DISPLAY INVISIBLE (-6025 4525);
FORCEPROP 1 LAST BODY_TYPE PLUMBING
J 0
(-6025 4575);
DISPLAY 0.872340 (-6025 4575);
PAINT GREEN (-6025 4575);
DISPLAY INVISIBLE (-6025 4575);
FORCEPROP 1 LAST HDL_TAP TRUE
J 0
(-5700 4400);
DISPLAY 0.872340 (-5700 4400);
DISPLAY INVISIBLE (-5700 4400);
FORCEPROP 1 LAST PATH I112
J 0
(-6027 4525);
DISPLAY 0.872340 (-6027 4525);
PAINT GREEN (-6027 4525);
DISPLAY INVISIBLE (-6027 4525);
FORCEADD TAP..1
(-6025 4575);
FORCEPROP 3 LASTPIN (-6075 4575) SIG_NAME M_L_CPU0_SA_DQ<21>
J 0
(-6065 4585);
DISPLAY 0.659574 (-6065 4585);
PAINT MONO (-6065 4585);
DISPLAY INVISIBLE (-6065 4585);
FORCEPROP 1 LASTPIN (-6075 4575) BN 21
J 0
(-6087 4583);
DISPLAY 0.489362 (-6087 4583);
PAINT GREEN (-6087 4583);
FORCEPROP 2 LAST CDS_LIB mstr_standard
J 0
(-6025 4575);
DISPLAY 0.723404 (-6025 4575);
PAINT MONO (-6025 4575);
DISPLAY INVISIBLE (-6025 4575);
FORCEPROP 1 LAST BODY_TYPE PLUMBING
J 0
(-6025 4625);
DISPLAY 0.872340 (-6025 4625);
PAINT GREEN (-6025 4625);
DISPLAY INVISIBLE (-6025 4625);
FORCEPROP 1 LAST HDL_TAP TRUE
J 0
(-5700 4450);
DISPLAY 0.872340 (-5700 4450);
DISPLAY INVISIBLE (-5700 4450);
FORCEPROP 1 LAST PATH I113
J 0
(-6027 4575);
DISPLAY 0.872340 (-6027 4575);
PAINT GREEN (-6027 4575);
DISPLAY INVISIBLE (-6027 4575);
FORCEADD TAP..1
(-6025 4625);
FORCEPROP 3 LASTPIN (-6075 4625) SIG_NAME M_L_CPU0_SA_DQ<22>
J 0
(-6065 4635);
DISPLAY 0.659574 (-6065 4635);
PAINT MONO (-6065 4635);
DISPLAY INVISIBLE (-6065 4635);
FORCEPROP 1 LASTPIN (-6075 4625) BN 22
J 0
(-6087 4633);
DISPLAY 0.489362 (-6087 4633);
PAINT GREEN (-6087 4633);
FORCEPROP 2 LAST CDS_LIB mstr_standard
J 0
(-6025 4625);
DISPLAY 0.723404 (-6025 4625);
PAINT MONO (-6025 4625);
DISPLAY INVISIBLE (-6025 4625);
FORCEPROP 1 LAST BODY_TYPE PLUMBING
J 0
(-6025 4675);
DISPLAY 0.872340 (-6025 4675);
PAINT GREEN (-6025 4675);
DISPLAY INVISIBLE (-6025 4675);
FORCEPROP 1 LAST HDL_TAP TRUE
J 0
(-5700 4500);
DISPLAY 0.872340 (-5700 4500);
DISPLAY INVISIBLE (-5700 4500);
FORCEPROP 1 LAST PATH I114
J 0
(-6027 4625);
DISPLAY 0.872340 (-6027 4625);
PAINT GREEN (-6027 4625);
DISPLAY INVISIBLE (-6027 4625);
FORCEADD TAP..1
(-6025 4675);
FORCEPROP 3 LASTPIN (-6075 4675) SIG_NAME M_L_CPU0_SA_DQ<23>
J 0
(-6065 4685);
DISPLAY 0.659574 (-6065 4685);
PAINT MONO (-6065 4685);
DISPLAY INVISIBLE (-6065 4685);
FORCEPROP 1 LASTPIN (-6075 4675) BN 23
J 0
(-6087 4683);
DISPLAY 0.489362 (-6087 4683);
PAINT GREEN (-6087 4683);
FORCEPROP 2 LAST CDS_LIB mstr_standard
J 0
(-6025 4675);
DISPLAY 0.723404 (-6025 4675);
PAINT MONO (-6025 4675);
DISPLAY INVISIBLE (-6025 4675);
FORCEPROP 1 LAST BODY_TYPE PLUMBING
J 0
(-6025 4725);
DISPLAY 0.872340 (-6025 4725);
PAINT GREEN (-6025 4725);
DISPLAY INVISIBLE (-6025 4725);
FORCEPROP 1 LAST HDL_TAP TRUE
J 0
(-5700 4550);
DISPLAY 0.872340 (-5700 4550);
DISPLAY INVISIBLE (-5700 4550);
FORCEPROP 1 LAST PATH I115
J 0
(-6027 4675);
DISPLAY 0.872340 (-6027 4675);
PAINT GREEN (-6027 4675);
DISPLAY INVISIBLE (-6027 4675);
FORCEADD TAP..1
(-6025 4725);
FORCEPROP 3 LASTPIN (-6075 4725) SIG_NAME M_L_CPU0_SA_DQ<24>
J 0
(-6065 4735);
DISPLAY 0.659574 (-6065 4735);
PAINT MONO (-6065 4735);
DISPLAY INVISIBLE (-6065 4735);
FORCEPROP 1 LASTPIN (-6075 4725) BN 24
J 0
(-6087 4733);
DISPLAY 0.489362 (-6087 4733);
PAINT GREEN (-6087 4733);
FORCEPROP 2 LAST CDS_LIB mstr_standard
J 0
(-6025 4725);
DISPLAY 0.723404 (-6025 4725);
PAINT MONO (-6025 4725);
DISPLAY INVISIBLE (-6025 4725);
FORCEPROP 1 LAST BODY_TYPE PLUMBING
J 0
(-6025 4775);
DISPLAY 0.872340 (-6025 4775);
PAINT GREEN (-6025 4775);
DISPLAY INVISIBLE (-6025 4775);
FORCEPROP 1 LAST HDL_TAP TRUE
J 0
(-5700 4600);
DISPLAY 0.872340 (-5700 4600);
DISPLAY INVISIBLE (-5700 4600);
FORCEPROP 1 LAST PATH I116
J 0
(-6027 4725);
DISPLAY 0.872340 (-6027 4725);
PAINT GREEN (-6027 4725);
DISPLAY INVISIBLE (-6027 4725);
FORCEADD TAP..1
(-6025 4775);
FORCEPROP 3 LASTPIN (-6075 4775) SIG_NAME M_L_CPU0_SA_DQ<25>
J 0
(-6065 4785);
DISPLAY 0.659574 (-6065 4785);
PAINT MONO (-6065 4785);
DISPLAY INVISIBLE (-6065 4785);
FORCEPROP 1 LASTPIN (-6075 4775) BN 25
J 0
(-6087 4783);
DISPLAY 0.489362 (-6087 4783);
PAINT GREEN (-6087 4783);
FORCEPROP 2 LAST CDS_LIB mstr_standard
J 0
(-6025 4775);
DISPLAY 0.723404 (-6025 4775);
PAINT MONO (-6025 4775);
DISPLAY INVISIBLE (-6025 4775);
FORCEPROP 1 LAST BODY_TYPE PLUMBING
J 0
(-6025 4825);
DISPLAY 0.872340 (-6025 4825);
PAINT GREEN (-6025 4825);
DISPLAY INVISIBLE (-6025 4825);
FORCEPROP 1 LAST HDL_TAP TRUE
J 0
(-5700 4650);
DISPLAY 0.872340 (-5700 4650);
DISPLAY INVISIBLE (-5700 4650);
FORCEPROP 1 LAST PATH I117
J 0
(-6027 4775);
DISPLAY 0.872340 (-6027 4775);
PAINT GREEN (-6027 4775);
DISPLAY INVISIBLE (-6027 4775);
FORCEADD TAP..1
(-6025 4825);
FORCEPROP 3 LASTPIN (-6075 4825) SIG_NAME M_L_CPU0_SA_DQ<26>
J 0
(-6065 4835);
DISPLAY 0.659574 (-6065 4835);
PAINT MONO (-6065 4835);
DISPLAY INVISIBLE (-6065 4835);
FORCEPROP 1 LASTPIN (-6075 4825) BN 26
J 0
(-6087 4833);
DISPLAY 0.489362 (-6087 4833);
PAINT GREEN (-6087 4833);
FORCEPROP 2 LAST CDS_LIB mstr_standard
J 0
(-6025 4825);
DISPLAY 0.723404 (-6025 4825);
PAINT MONO (-6025 4825);
DISPLAY INVISIBLE (-6025 4825);
FORCEPROP 1 LAST BODY_TYPE PLUMBING
J 0
(-6025 4875);
DISPLAY 0.872340 (-6025 4875);
PAINT GREEN (-6025 4875);
DISPLAY INVISIBLE (-6025 4875);
FORCEPROP 1 LAST HDL_TAP TRUE
J 0
(-5700 4700);
DISPLAY 0.872340 (-5700 4700);
DISPLAY INVISIBLE (-5700 4700);
FORCEPROP 1 LAST PATH I118
J 0
(-6027 4825);
DISPLAY 0.872340 (-6027 4825);
PAINT GREEN (-6027 4825);
DISPLAY INVISIBLE (-6027 4825);
FORCEADD TAP..1
(-6025 4875);
FORCEPROP 3 LASTPIN (-6075 4875) SIG_NAME M_L_CPU0_SA_DQ<27>
J 0
(-6065 4885);
DISPLAY 0.659574 (-6065 4885);
PAINT MONO (-6065 4885);
DISPLAY INVISIBLE (-6065 4885);
FORCEPROP 1 LASTPIN (-6075 4875) BN 27
J 0
(-6087 4883);
DISPLAY 0.489362 (-6087 4883);
PAINT GREEN (-6087 4883);
FORCEPROP 2 LAST CDS_LIB mstr_standard
J 0
(-6025 4875);
DISPLAY 0.723404 (-6025 4875);
PAINT MONO (-6025 4875);
DISPLAY INVISIBLE (-6025 4875);
FORCEPROP 1 LAST BODY_TYPE PLUMBING
J 0
(-6025 4925);
DISPLAY 0.872340 (-6025 4925);
PAINT GREEN (-6025 4925);
DISPLAY INVISIBLE (-6025 4925);
FORCEPROP 1 LAST HDL_TAP TRUE
J 0
(-5700 4750);
DISPLAY 0.872340 (-5700 4750);
DISPLAY INVISIBLE (-5700 4750);
FORCEPROP 1 LAST PATH I119
J 0
(-6027 4875);
DISPLAY 0.872340 (-6027 4875);
PAINT GREEN (-6027 4875);
DISPLAY INVISIBLE (-6027 4875);
FORCEADD OFFPAGE..1
(-8325 3775);
FORCEPROP 2 LAST $XR0 21 
J 0
(-8546 3775);
DISPLAY 0.638298 (-8546 3775);
PAINT MONO (-8546 3775);
FORCEPROP 2 LAST CDS_LIB mstr_standard
J 0
(-8325 3775);
DISPLAY 0.808511 (-8325 3775);
DISPLAY INVISIBLE (-8325 3775);
FORCEPROP 1 LAST OFFPAGE TRUE
J 0
(-8000 3650);
DISPLAY 0.872340 (-8000 3650);
PAINT GREEN (-8000 3650);
DISPLAY INVISIBLE (-8000 3650);
FORCEPROP 1 LAST COMMENT_BODY TRUE
J 0
(-8200 3675);
DISPLAY 0.872340 (-8200 3675);
PAINT GREEN (-8200 3675);
DISPLAY INVISIBLE (-8200 3675);
FORCEPROP 2 LAST PATH I12
J 0
(-8275 3850);
DISPLAY 1.021277 (-8275 3850);
DISPLAY INVISIBLE (-8275 3850);
FORCEADD TAP..1
(-6025 4925);
FORCEPROP 3 LASTPIN (-6075 4925) SIG_NAME M_L_CPU0_SA_DQ<28>
J 0
(-6065 4935);
DISPLAY 0.659574 (-6065 4935);
PAINT MONO (-6065 4935);
DISPLAY INVISIBLE (-6065 4935);
FORCEPROP 1 LASTPIN (-6075 4925) BN 28
J 0
(-6087 4933);
DISPLAY 0.489362 (-6087 4933);
PAINT GREEN (-6087 4933);
FORCEPROP 2 LAST CDS_LIB mstr_standard
J 0
(-6025 4925);
DISPLAY 0.723404 (-6025 4925);
PAINT MONO (-6025 4925);
DISPLAY INVISIBLE (-6025 4925);
FORCEPROP 1 LAST BODY_TYPE PLUMBING
J 0
(-6025 4975);
DISPLAY 0.872340 (-6025 4975);
PAINT GREEN (-6025 4975);
DISPLAY INVISIBLE (-6025 4975);
FORCEPROP 1 LAST HDL_TAP TRUE
J 0
(-5700 4800);
DISPLAY 0.872340 (-5700 4800);
DISPLAY INVISIBLE (-5700 4800);
FORCEPROP 1 LAST PATH I120
J 0
(-6027 4925);
DISPLAY 0.872340 (-6027 4925);
PAINT GREEN (-6027 4925);
DISPLAY INVISIBLE (-6027 4925);
FORCEADD TAP..1
(-6025 5025);
FORCEPROP 3 LASTPIN (-6075 5025) SIG_NAME M_L_CPU0_SA_DQ<30>
J 0
(-6065 5035);
DISPLAY 0.659574 (-6065 5035);
PAINT MONO (-6065 5035);
DISPLAY INVISIBLE (-6065 5035);
FORCEPROP 1 LASTPIN (-6075 5025) BN 30
J 0
(-6087 5033);
DISPLAY 0.489362 (-6087 5033);
PAINT GREEN (-6087 5033);
FORCEPROP 2 LAST CDS_LIB mstr_standard
J 0
(-6025 5025);
DISPLAY 0.723404 (-6025 5025);
PAINT MONO (-6025 5025);
DISPLAY INVISIBLE (-6025 5025);
FORCEPROP 1 LAST BODY_TYPE PLUMBING
J 0
(-6025 5075);
DISPLAY 0.872340 (-6025 5075);
PAINT GREEN (-6025 5075);
DISPLAY INVISIBLE (-6025 5075);
FORCEPROP 1 LAST HDL_TAP TRUE
J 0
(-5700 4900);
DISPLAY 0.872340 (-5700 4900);
DISPLAY INVISIBLE (-5700 4900);
FORCEPROP 1 LAST PATH I121
J 0
(-6027 5025);
DISPLAY 0.872340 (-6027 5025);
PAINT GREEN (-6027 5025);
DISPLAY INVISIBLE (-6027 5025);
FORCEADD TAP..1
(-6025 5075);
FORCEPROP 3 LASTPIN (-6075 5075) SIG_NAME M_L_CPU0_SA_DQ<31>
J 0
(-6065 5085);
DISPLAY 0.659574 (-6065 5085);
PAINT MONO (-6065 5085);
DISPLAY INVISIBLE (-6065 5085);
FORCEPROP 1 LASTPIN (-6075 5075) BN 31
J 0
(-6087 5083);
DISPLAY 0.489362 (-6087 5083);
PAINT GREEN (-6087 5083);
FORCEPROP 2 LAST CDS_LIB mstr_standard
J 0
(-6025 5075);
DISPLAY 0.723404 (-6025 5075);
PAINT MONO (-6025 5075);
DISPLAY INVISIBLE (-6025 5075);
FORCEPROP 1 LAST BODY_TYPE PLUMBING
J 0
(-6025 5125);
DISPLAY 0.872340 (-6025 5125);
PAINT GREEN (-6025 5125);
DISPLAY INVISIBLE (-6025 5125);
FORCEPROP 1 LAST HDL_TAP TRUE
J 0
(-5700 4950);
DISPLAY 0.872340 (-5700 4950);
DISPLAY INVISIBLE (-5700 4950);
FORCEPROP 1 LAST PATH I122
J 0
(-6027 5075);
DISPLAY 0.872340 (-6027 5075);
PAINT GREEN (-6027 5075);
DISPLAY INVISIBLE (-6027 5075);
FORCEADD TAP..1
(-6025 4975);
FORCEPROP 3 LASTPIN (-6075 4975) SIG_NAME M_L_CPU0_SA_DQ<29>
J 0
(-6065 4985);
DISPLAY 0.659574 (-6065 4985);
PAINT MONO (-6065 4985);
DISPLAY INVISIBLE (-6065 4985);
FORCEPROP 1 LASTPIN (-6075 4975) BN 29
J 0
(-6087 4983);
DISPLAY 0.489362 (-6087 4983);
PAINT GREEN (-6087 4983);
FORCEPROP 2 LAST CDS_LIB mstr_standard
J 0
(-6025 4975);
DISPLAY 0.723404 (-6025 4975);
PAINT MONO (-6025 4975);
DISPLAY INVISIBLE (-6025 4975);
FORCEPROP 1 LAST BODY_TYPE PLUMBING
J 0
(-6025 5025);
DISPLAY 0.872340 (-6025 5025);
PAINT GREEN (-6025 5025);
DISPLAY INVISIBLE (-6025 5025);
FORCEPROP 1 LAST HDL_TAP TRUE
J 0
(-5700 4850);
DISPLAY 0.872340 (-5700 4850);
DISPLAY INVISIBLE (-5700 4850);
FORCEPROP 1 LAST PATH I123
J 0
(-6027 4975);
DISPLAY 0.872340 (-6027 4975);
PAINT GREEN (-6027 4975);
DISPLAY INVISIBLE (-6027 4975);
FORCEADD OFFPAGE..3
(-5350 3450);
FORCEPROP 2 LAST $XR0 21 
J 0
(-5136 3450);
DISPLAY 0.638298 (-5136 3450);
PAINT MONO (-5136 3450);
FORCEPROP 2 LAST CDS_LIB mstr_standard
J 0
(-5350 3450);
DISPLAY 0.723404 (-5350 3450);
PAINT MONO (-5350 3450);
DISPLAY INVISIBLE (-5350 3450);
FORCEPROP 1 LAST OFFPAGE TRUE
J 0
(-5025 3325);
DISPLAY 0.872340 (-5025 3325);
PAINT GREEN (-5025 3325);
DISPLAY INVISIBLE (-5025 3325);
FORCEPROP 1 LAST COMMENT_BODY TRUE
J 0
(-5400 3350);
DISPLAY 0.872340 (-5400 3350);
PAINT GREEN (-5400 3350);
DISPLAY INVISIBLE (-5400 3350);
FORCEPROP 2 LAST PATH I124
J 0
(-5150 3525);
DISPLAY 1.021277 (-5150 3525);
DISPLAY INVISIBLE (-5150 3525);
FORCEADD OFFPAGE..3
(-5350 5100);
FORCEPROP 2 LAST $XR0 21 
J 0
(-5136 5100);
DISPLAY 0.638298 (-5136 5100);
PAINT MONO (-5136 5100);
FORCEPROP 2 LAST CDS_LIB mstr_standard
J 0
(-5350 5100);
DISPLAY 0.723404 (-5350 5100);
PAINT MONO (-5350 5100);
DISPLAY INVISIBLE (-5350 5100);
FORCEPROP 1 LAST OFFPAGE TRUE
J 0
(-5025 4975);
DISPLAY 0.872340 (-5025 4975);
PAINT GREEN (-5025 4975);
DISPLAY INVISIBLE (-5025 4975);
FORCEPROP 1 LAST COMMENT_BODY TRUE
J 0
(-5400 5000);
DISPLAY 0.872340 (-5400 5000);
PAINT GREEN (-5400 5000);
DISPLAY INVISIBLE (-5400 5000);
FORCEPROP 2 LAST PATH I125
J 0
(-5150 5175);
DISPLAY 1.021277 (-5150 5175);
DISPLAY INVISIBLE (-5150 5175);
FORCEADD GND..1
(-6450 700);
FORCEPROP 3 LASTPIN (-6450 750) SIG_NAME GND\g
J 0
(-6440 760);
DISPLAY 0.659574 (-6440 760);
PAINT MONO (-6440 760);
DISPLAY INVISIBLE (-6440 760);
FORCEPROP 2 LAST BOM_COST MEM
J 0
(-6550 775);
DISPLAY 0.808511 (-6550 775);
DISPLAY INVISIBLE (-6550 775);
FORCEPROP 1 LAST SIZE 1B
J 0
(-6375 650);
DISPLAY 0.851064 (-6375 650);
PAINT GREEN (-6375 650);
DISPLAY INVISIBLE (-6375 650);
FORCEPROP 2 LAST CDS_LIB mstr_symbols
J 0
(-6450 700);
DISPLAY 0.808511 (-6450 700);
DISPLAY INVISIBLE (-6450 700);
FORCEPROP 1 LAST BODY_TYPE PLUMBING
J 0
(-6495 657);
DISPLAY 0.340426 (-6495 657);
PAINT GREEN (-6495 657);
DISPLAY INVISIBLE (-6495 657);
FORCEPROP 1 LAST PATH I126
J 0
(-6375 700);
DISPLAY 0.872340 (-6375 700);
PAINT AQUA (-6375 700);
DISPLAY INVISIBLE (-6375 700);
FORCEPROP 1 LAST VOLTAGE 0.0
J 0
(-6495 657);
DISPLAY 0.723404 (-6495 657);
PAINT SKYBLUE (-6495 657);
DISPLAY INVISIBLE (-6495 657);
FORCEPROP 1 LAST HDL_POWER GND
J 0
(-6450 850);
DISPLAY 0.851064 (-6450 850);
PAINT GREEN (-6450 850);
DISPLAY INVISIBLE (-6450 850);
FORCEADD Q_RES..2
(-6450 925);
FORCEPROP 1 LAST LOCATION R769
J 0
(-6405 1050);
DISPLAY 0.489362 (-6405 1050);
PAINT SKYBLUE (-6405 1050);
FORCEPROP 0 LAST $SEC 1
J 0
(-6400 1100);
DISPLAY 0.680851 (-6400 1100);
PAINT MONO (-6400 1100);
DISPLAY INVISIBLE (-6400 1100);
FORCEPROP 0 LAST CDS_SEC 1
J 0
(-6400 1100);
DISPLAY 1.021277 (-6400 1100);
DISPLAY INVISIBLE (-6400 1100);
FORCEPROP 1 LASTPIN (-6450 1025) $PN 1
J 0
(-6445 987);
DISPLAY 0.489362 (-6445 987);
PAINT MONO (-6445 987);
FORCEPROP 1 LASTPIN (-6450 825) $PN 2
J 0
(-6445 835);
DISPLAY 0.489362 (-6445 835);
PAINT MONO (-6445 835);
FORCEPROP 1 LAST WATTAGE 1/16W
J 0
(-6410 900);
DISPLAY 0.489362 (-6410 900);
PAINT SKYBLUE (-6410 900);
FORCEPROP 1 LAST MATERIAL CHIP
J 0
(-6410 850);
DISPLAY 0.489362 (-6410 850);
PAINT SKYBLUE (-6410 850);
FORCEPROP 1 LAST TOLERANCE 1%
J 0
(-6405 950);
DISPLAY 0.489362 (-6405 950);
PAINT SKYBLUE (-6405 950);
FORCEPROP 1 LAST VALUE 84.5K
J 0
(-6405 1000);
DISPLAY 0.489362 (-6405 1000);
PAINT SKYBLUE (-6405 1000);
FORCEPROP 1 LAST PART_NUMBER CS38452FB05
J 0
(-6410 800);
DISPLAY 0.489362 (-6410 800);
PAINT SKYBLUE (-6410 800);
FORCEPROP 1 LAST PACK_TYPE 0402LF
J 0
(-6410 750);
DISPLAY 0.489362 (-6410 750);
PAINT SKYBLUE (-6410 750);
FORCEPROP 2 LAST CDS_LIB pure_quanta
J 0
(-6450 925);
DISPLAY INVISIBLE (-6450 925);
FORCEPROP 1 LAST PATH I127
J 0
(-6400 1100);
DISPLAY 0.978723 (-6400 1100);
PAINT WHITE (-6400 1100);
DISPLAY INVISIBLE (-6400 1100);
FORCEADD OFFPAGE..5
(-7225 1100);
FORCEPROP 2 LAST $XR0 96 
J 0
(-7449 1100);
DISPLAY 0.638298 (-7449 1100);
PAINT MONO (-7449 1100);
FORCEPROP 2 LAST BOM_COST MEM
J 0
(-7300 1175);
DISPLAY 0.808511 (-7300 1175);
DISPLAY INVISIBLE (-7300 1175);
FORCEPROP 2 LAST CDS_LIB mstr_standard
J 0
(-7225 1100);
DISPLAY 0.808511 (-7225 1100);
DISPLAY INVISIBLE (-7225 1100);
FORCEPROP 1 LAST OFFPAGE TRUE
J 0
(-6900 975);
DISPLAY 0.872340 (-6900 975);
PAINT GREEN (-6900 975);
DISPLAY INVISIBLE (-6900 975);
FORCEPROP 1 LAST COMMENT_BODY TRUE
J 0
(-7125 1025);
DISPLAY 0.872340 (-7125 1025);
PAINT GREEN (-7125 1025);
DISPLAY INVISIBLE (-7125 1025);
FORCEPROP 2 LAST PATH I128
J 0
(-7475 1150);
DISPLAY 1.021277 (-7475 1150);
DISPLAY INVISIBLE (-7475 1150);
FORCEADD OFFPAGE..6
(-8325 3725);
FORCEPROP 2 LAST $XR0 21 
J 0
(-8574 3725);
DISPLAY 0.638298 (-8574 3725);
PAINT MONO (-8574 3725);
FORCEPROP 2 LAST CDS_LIB mstr_standard
J 0
(-8325 3725);
DISPLAY 0.723404 (-8325 3725);
PAINT MONO (-8325 3725);
DISPLAY INVISIBLE (-8325 3725);
FORCEPROP 1 LAST OFFPAGE TRUE
J 0
(-8000 3600);
DISPLAY 0.872340 (-8000 3600);
PAINT GREEN (-8000 3600);
DISPLAY INVISIBLE (-8000 3600);
FORCEPROP 1 LAST COMMENT_BODY TRUE
J 0
(-8225 3650);
DISPLAY 0.872340 (-8225 3650);
PAINT GREEN (-8225 3650);
DISPLAY INVISIBLE (-8225 3650);
FORCEPROP 2 LAST PATH I13
J 0
(-8275 3800);
DISPLAY 1.021277 (-8275 3800);
DISPLAY INVISIBLE (-8275 3800);
FORCEADD GND..1
(-2200 1750);
FORCEPROP 3 LASTPIN (-2200 1800) SIG_NAME GND\g
J 0
(-2190 1810);
DISPLAY 0.659574 (-2190 1810);
PAINT MONO (-2190 1810);
DISPLAY INVISIBLE (-2190 1810);
FORCEPROP 2 LAST CDS_LIB mstr_symbols
J 0
(-2200 1750);
DISPLAY 0.723404 (-2200 1750);
DISPLAY INVISIBLE (-2200 1750);
FORCEPROP 1 LAST SIZE 1B
J 0
(-2125 1700);
DISPLAY 0.851064 (-2125 1700);
PAINT GREEN (-2125 1700);
DISPLAY INVISIBLE (-2125 1700);
FORCEPROP 1 LAST BODY_TYPE PLUMBING
J 0
(-2245 1707);
DISPLAY 0.340426 (-2245 1707);
PAINT GREEN (-2245 1707);
DISPLAY INVISIBLE (-2245 1707);
FORCEPROP 1 LAST PATH I138
J 0
(-2125 1750);
DISPLAY 0.872340 (-2125 1750);
PAINT AQUA (-2125 1750);
DISPLAY INVISIBLE (-2125 1750);
FORCEPROP 1 LAST VOLTAGE 0.0
J 0
(-2245 1707);
DISPLAY 0.723404 (-2245 1707);
PAINT SKYBLUE (-2245 1707);
DISPLAY INVISIBLE (-2245 1707);
FORCEPROP 1 LAST HDL_POWER GND
J 0
(-2200 1900);
DISPLAY 0.851064 (-2200 1900);
PAINT GREEN (-2200 1900);
DISPLAY INVISIBLE (-2200 1900);
FORCEADD GND..1
(-400 1525);
FORCEPROP 3 LASTPIN (-400 1575) SIG_NAME GND\g
J 0
(-390 1585);
DISPLAY 0.659574 (-390 1585);
PAINT MONO (-390 1585);
DISPLAY INVISIBLE (-390 1585);
FORCEPROP 2 LAST CDS_LIB mstr_symbols
J 0
(-400 1525);
DISPLAY 0.723404 (-400 1525);
DISPLAY INVISIBLE (-400 1525);
FORCEPROP 1 LAST SIZE 1B
J 0
(-325 1475);
DISPLAY 0.851064 (-325 1475);
PAINT GREEN (-325 1475);
DISPLAY INVISIBLE (-325 1475);
FORCEPROP 1 LAST BODY_TYPE PLUMBING
J 0
(-445 1482);
DISPLAY 0.340426 (-445 1482);
PAINT GREEN (-445 1482);
DISPLAY INVISIBLE (-445 1482);
FORCEPROP 1 LAST PATH I139
J 0
(-325 1525);
DISPLAY 0.872340 (-325 1525);
PAINT AQUA (-325 1525);
DISPLAY INVISIBLE (-325 1525);
FORCEPROP 1 LAST VOLTAGE 0.0
J 0
(-445 1482);
DISPLAY 0.723404 (-445 1482);
PAINT SKYBLUE (-445 1482);
DISPLAY INVISIBLE (-445 1482);
FORCEPROP 1 LAST HDL_POWER GND
J 0
(-400 1675);
DISPLAY 0.851064 (-400 1675);
PAINT GREEN (-400 1675);
DISPLAY INVISIBLE (-400 1675);
FORCEADD OFFPAGE..1
(-8325 3925);
FORCEPROP 2 LAST $XR0 21 
J 0
(-8546 3925);
DISPLAY 0.638298 (-8546 3925);
PAINT MONO (-8546 3925);
FORCEPROP 2 LAST CDS_LIB mstr_standard
J 0
(-8325 3925);
DISPLAY 0.808511 (-8325 3925);
DISPLAY INVISIBLE (-8325 3925);
FORCEPROP 1 LAST OFFPAGE TRUE
J 0
(-8000 3800);
DISPLAY 0.872340 (-8000 3800);
PAINT GREEN (-8000 3800);
DISPLAY INVISIBLE (-8000 3800);
FORCEPROP 1 LAST COMMENT_BODY TRUE
J 0
(-8200 3825);
DISPLAY 0.872340 (-8200 3825);
PAINT GREEN (-8200 3825);
DISPLAY INVISIBLE (-8200 3825);
FORCEPROP 2 LAST PATH I14
J 0
(-8275 4000);
DISPLAY 1.021277 (-8275 4000);
DISPLAY INVISIBLE (-8275 4000);
FORCEADD SCONN288_DDR506112002KQ..3
(-1300 3525);
FORCEPROP 1 LAST LOCATION J67
J 0
(-1750 5500);
DISPLAY 0.468085 (-1750 5500);
PAINT SKYBLUE (-1750 5500);
FORCEPROP 0 LAST $SEC 3
J 0
(-1750 5650);
DISPLAY 0.680851 (-1750 5650);
PAINT MONO (-1750 5650);
DISPLAY INVISIBLE (-1750 5650);
FORCEPROP 2 LAST CDS_SEC 3
J 0
(-1750 5650);
DISPLAY 1.021277 (-1750 5650);
DISPLAY INVISIBLE (-1750 5650);
FORCEPROP 0 LASTPIN (-700 1925) $PN G1
J 0
(-690 1935);
DISPLAY 0.680851 (-690 1935);
PAINT MONO (-690 1935);
FORCEPROP 0 LASTPIN (-700 1875) $PN G2
J 0
(-690 1885);
DISPLAY 0.680851 (-690 1885);
PAINT MONO (-690 1885);
FORCEPROP 0 LASTPIN (-700 1825) $PN G3
J 0
(-690 1835);
DISPLAY 0.680851 (-690 1835);
PAINT MONO (-690 1835);
FORCEPROP 0 LASTPIN (-1900 5075) $PN 1
J 2
(-1910 5085);
DISPLAY 0.680851 (-1910 5085);
PAINT MONO (-1910 5085);
FORCEPROP 0 LASTPIN (-1900 5125) $PN 145
J 2
(-1910 5135);
DISPLAY 0.680851 (-1910 5135);
PAINT MONO (-1910 5135);
FORCEPROP 0 LASTPIN (-1900 5175) $PN 146
J 2
(-1910 5185);
DISPLAY 0.680851 (-1910 5185);
PAINT MONO (-1910 5185);
FORCEPROP 0 LASTPIN (-700 2025) $PN 6
J 0
(-690 2035);
DISPLAY 0.680851 (-690 2035);
PAINT MONO (-690 2035);
FORCEPROP 0 LASTPIN (-700 2075) $PN 8
J 0
(-690 2085);
DISPLAY 0.680851 (-690 2085);
PAINT MONO (-690 2085);
FORCEPROP 0 LASTPIN (-700 2125) $PN 10
J 0
(-690 2135);
DISPLAY 0.680851 (-690 2135);
PAINT MONO (-690 2135);
FORCEPROP 0 LASTPIN (-700 2175) $PN 13
J 0
(-690 2185);
DISPLAY 0.680851 (-690 2185);
PAINT MONO (-690 2185);
FORCEPROP 0 LASTPIN (-700 2225) $PN 15
J 0
(-690 2235);
DISPLAY 0.680851 (-690 2235);
PAINT MONO (-690 2235);
FORCEPROP 0 LASTPIN (-700 2275) $PN 17
J 0
(-690 2285);
DISPLAY 0.680851 (-690 2285);
PAINT MONO (-690 2285);
FORCEPROP 0 LASTPIN (-700 2325) $PN 19
J 0
(-690 2335);
DISPLAY 0.680851 (-690 2335);
PAINT MONO (-690 2335);
FORCEPROP 0 LASTPIN (-700 2375) $PN 21
J 0
(-690 2385);
DISPLAY 0.680851 (-690 2385);
PAINT MONO (-690 2385);
FORCEPROP 0 LASTPIN (-700 2425) $PN 24
J 0
(-690 2435);
DISPLAY 0.680851 (-690 2435);
PAINT MONO (-690 2435);
FORCEPROP 0 LASTPIN (-700 2475) $PN 26
J 0
(-690 2485);
DISPLAY 0.680851 (-690 2485);
PAINT MONO (-690 2485);
FORCEPROP 0 LASTPIN (-700 2525) $PN 28
J 0
(-690 2535);
DISPLAY 0.680851 (-690 2535);
PAINT MONO (-690 2535);
FORCEPROP 0 LASTPIN (-700 2575) $PN 30
J 0
(-690 2585);
DISPLAY 0.680851 (-690 2585);
PAINT MONO (-690 2585);
FORCEPROP 0 LASTPIN (-700 2625) $PN 32
J 0
(-690 2635);
DISPLAY 0.680851 (-690 2635);
PAINT MONO (-690 2635);
FORCEPROP 0 LASTPIN (-700 2675) $PN 35
J 0
(-690 2685);
DISPLAY 0.680851 (-690 2685);
PAINT MONO (-690 2685);
FORCEPROP 0 LASTPIN (-700 2725) $PN 37
J 0
(-690 2735);
DISPLAY 0.680851 (-690 2735);
PAINT MONO (-690 2735);
FORCEPROP 0 LASTPIN (-700 2775) $PN 39
J 0
(-690 2785);
DISPLAY 0.680851 (-690 2785);
PAINT MONO (-690 2785);
FORCEPROP 0 LASTPIN (-700 2825) $PN 41
J 0
(-690 2835);
DISPLAY 0.680851 (-690 2835);
PAINT MONO (-690 2835);
FORCEPROP 0 LASTPIN (-700 2875) $PN 43
J 0
(-690 2885);
DISPLAY 0.680851 (-690 2885);
PAINT MONO (-690 2885);
FORCEPROP 0 LASTPIN (-700 2925) $PN 46
J 0
(-690 2935);
DISPLAY 0.680851 (-690 2935);
PAINT MONO (-690 2935);
FORCEPROP 0 LASTPIN (-700 2975) $PN 48
J 0
(-690 2985);
DISPLAY 0.680851 (-690 2985);
PAINT MONO (-690 2985);
FORCEPROP 0 LASTPIN (-700 3025) $PN 50
J 0
(-690 3035);
DISPLAY 0.680851 (-690 3035);
PAINT MONO (-690 3035);
FORCEPROP 0 LASTPIN (-700 3075) $PN 52
J 0
(-690 3085);
DISPLAY 0.680851 (-690 3085);
PAINT MONO (-690 3085);
FORCEPROP 0 LASTPIN (-700 3125) $PN 54
J 0
(-690 3135);
DISPLAY 0.680851 (-690 3135);
PAINT MONO (-690 3135);
FORCEPROP 0 LASTPIN (-700 3175) $PN 57
J 0
(-690 3185);
DISPLAY 0.680851 (-690 3185);
PAINT MONO (-690 3185);
FORCEPROP 0 LASTPIN (-700 3225) $PN 59
J 0
(-690 3235);
DISPLAY 0.680851 (-690 3235);
PAINT MONO (-690 3235);
FORCEPROP 0 LASTPIN (-700 3275) $PN 61
J 0
(-690 3285);
DISPLAY 0.680851 (-690 3285);
PAINT MONO (-690 3285);
FORCEPROP 0 LASTPIN (-700 3325) $PN 63
J 0
(-690 3335);
DISPLAY 0.680851 (-690 3335);
PAINT MONO (-690 3335);
FORCEPROP 0 LASTPIN (-700 3375) $PN 65
J 0
(-690 3385);
DISPLAY 0.680851 (-690 3385);
PAINT MONO (-690 3385);
FORCEPROP 0 LASTPIN (-700 3425) $PN 67
J 0
(-690 3435);
DISPLAY 0.680851 (-690 3435);
PAINT MONO (-690 3435);
FORCEPROP 0 LASTPIN (-700 3475) $PN 69
J 0
(-690 3485);
DISPLAY 0.680851 (-690 3485);
PAINT MONO (-690 3485);
FORCEPROP 0 LASTPIN (-700 3525) $PN 71
J 0
(-690 3535);
DISPLAY 0.680851 (-690 3535);
PAINT MONO (-690 3535);
FORCEPROP 0 LASTPIN (-700 3575) $PN 73
J 0
(-690 3585);
DISPLAY 0.680851 (-690 3585);
PAINT MONO (-690 3585);
FORCEPROP 0 LASTPIN (-700 3625) $PN 75
J 0
(-690 3635);
DISPLAY 0.680851 (-690 3635);
PAINT MONO (-690 3635);
FORCEPROP 0 LASTPIN (-700 3675) $PN 77
J 0
(-690 3685);
DISPLAY 0.680851 (-690 3685);
PAINT MONO (-690 3685);
FORCEPROP 0 LASTPIN (-700 3725) $PN 79
J 0
(-690 3735);
DISPLAY 0.680851 (-690 3735);
PAINT MONO (-690 3735);
FORCEPROP 0 LASTPIN (-700 3775) $PN 81
J 0
(-690 3785);
DISPLAY 0.680851 (-690 3785);
PAINT MONO (-690 3785);
FORCEPROP 0 LASTPIN (-700 3825) $PN 83
J 0
(-690 3835);
DISPLAY 0.680851 (-690 3835);
PAINT MONO (-690 3835);
FORCEPROP 0 LASTPIN (-700 3875) $PN 85
J 0
(-690 3885);
DISPLAY 0.680851 (-690 3885);
PAINT MONO (-690 3885);
FORCEPROP 0 LASTPIN (-700 3925) $PN 88
J 0
(-690 3935);
DISPLAY 0.680851 (-690 3935);
PAINT MONO (-690 3935);
FORCEPROP 0 LASTPIN (-700 3975) $PN 90
J 0
(-690 3985);
DISPLAY 0.680851 (-690 3985);
PAINT MONO (-690 3985);
FORCEPROP 0 LASTPIN (-700 4025) $PN 92
J 0
(-690 4035);
DISPLAY 0.680851 (-690 4035);
PAINT MONO (-690 4035);
FORCEPROP 0 LASTPIN (-700 4075) $PN 95
J 0
(-690 4085);
DISPLAY 0.680851 (-690 4085);
PAINT MONO (-690 4085);
FORCEPROP 0 LASTPIN (-700 4125) $PN 97
J 0
(-690 4135);
DISPLAY 0.680851 (-690 4135);
PAINT MONO (-690 4135);
FORCEPROP 0 LASTPIN (-700 4175) $PN 99
J 0
(-690 4185);
DISPLAY 0.680851 (-690 4185);
PAINT MONO (-690 4185);
FORCEPROP 0 LASTPIN (-700 4225) $PN 101
J 0
(-690 4235);
DISPLAY 0.680851 (-690 4235);
PAINT MONO (-690 4235);
FORCEPROP 0 LASTPIN (-700 4275) $PN 103
J 0
(-690 4285);
DISPLAY 0.680851 (-690 4285);
PAINT MONO (-690 4285);
FORCEPROP 0 LASTPIN (-700 4325) $PN 106
J 0
(-690 4335);
DISPLAY 0.680851 (-690 4335);
PAINT MONO (-690 4335);
FORCEPROP 0 LASTPIN (-700 4375) $PN 108
J 0
(-690 4385);
DISPLAY 0.680851 (-690 4385);
PAINT MONO (-690 4385);
FORCEPROP 0 LASTPIN (-700 4425) $PN 110
J 0
(-690 4435);
DISPLAY 0.680851 (-690 4435);
PAINT MONO (-690 4435);
FORCEPROP 0 LASTPIN (-700 4475) $PN 112
J 0
(-690 4485);
DISPLAY 0.680851 (-690 4485);
PAINT MONO (-690 4485);
FORCEPROP 0 LASTPIN (-700 4525) $PN 114
J 0
(-690 4535);
DISPLAY 0.680851 (-690 4535);
PAINT MONO (-690 4535);
FORCEPROP 0 LASTPIN (-700 4575) $PN 117
J 0
(-690 4585);
DISPLAY 0.680851 (-690 4585);
PAINT MONO (-690 4585);
FORCEPROP 0 LASTPIN (-700 4625) $PN 119
J 0
(-690 4635);
DISPLAY 0.680851 (-690 4635);
PAINT MONO (-690 4635);
FORCEPROP 0 LASTPIN (-700 4675) $PN 121
J 0
(-690 4685);
DISPLAY 0.680851 (-690 4685);
PAINT MONO (-690 4685);
FORCEPROP 0 LASTPIN (-700 4725) $PN 123
J 0
(-690 4735);
DISPLAY 0.680851 (-690 4735);
PAINT MONO (-690 4735);
FORCEPROP 0 LASTPIN (-700 4775) $PN 125
J 0
(-690 4785);
DISPLAY 0.680851 (-690 4785);
PAINT MONO (-690 4785);
FORCEPROP 0 LASTPIN (-700 4825) $PN 128
J 0
(-690 4835);
DISPLAY 0.680851 (-690 4835);
PAINT MONO (-690 4835);
FORCEPROP 0 LASTPIN (-700 4875) $PN 130
J 0
(-690 4885);
DISPLAY 0.680851 (-690 4885);
PAINT MONO (-690 4885);
FORCEPROP 0 LASTPIN (-700 4925) $PN 132
J 0
(-690 4935);
DISPLAY 0.680851 (-690 4935);
PAINT MONO (-690 4935);
FORCEPROP 0 LASTPIN (-700 4975) $PN 134
J 0
(-690 4985);
DISPLAY 0.680851 (-690 4985);
PAINT MONO (-690 4985);
FORCEPROP 0 LASTPIN (-700 5025) $PN 136
J 0
(-690 5035);
DISPLAY 0.680851 (-690 5035);
PAINT MONO (-690 5035);
FORCEPROP 0 LASTPIN (-700 5075) $PN 139
J 0
(-690 5085);
DISPLAY 0.680851 (-690 5085);
PAINT MONO (-690 5085);
FORCEPROP 0 LASTPIN (-700 5125) $PN 141
J 0
(-690 5135);
DISPLAY 0.680851 (-690 5135);
PAINT MONO (-690 5135);
FORCEPROP 0 LASTPIN (-700 5175) $PN 143
J 0
(-690 5185);
DISPLAY 0.680851 (-690 5185);
PAINT MONO (-690 5185);
FORCEPROP 0 LASTPIN (-1900 1925) $PN 151
J 2
(-1910 1935);
DISPLAY 0.680851 (-1910 1935);
PAINT MONO (-1910 1935);
FORCEPROP 0 LASTPIN (-1900 1975) $PN 153
J 2
(-1910 1985);
DISPLAY 0.680851 (-1910 1985);
PAINT MONO (-1910 1985);
FORCEPROP 0 LASTPIN (-1900 2025) $PN 155
J 2
(-1910 2035);
DISPLAY 0.680851 (-1910 2035);
PAINT MONO (-1910 2035);
FORCEPROP 0 LASTPIN (-1900 2075) $PN 158
J 2
(-1910 2085);
DISPLAY 0.680851 (-1910 2085);
PAINT MONO (-1910 2085);
FORCEPROP 0 LASTPIN (-1900 2125) $PN 160
J 2
(-1910 2135);
DISPLAY 0.680851 (-1910 2135);
PAINT MONO (-1910 2135);
FORCEPROP 0 LASTPIN (-1900 2175) $PN 162
J 2
(-1910 2185);
DISPLAY 0.680851 (-1910 2185);
PAINT MONO (-1910 2185);
FORCEPROP 0 LASTPIN (-1900 2225) $PN 164
J 2
(-1910 2235);
DISPLAY 0.680851 (-1910 2235);
PAINT MONO (-1910 2235);
FORCEPROP 0 LASTPIN (-1900 2275) $PN 166
J 2
(-1910 2285);
DISPLAY 0.680851 (-1910 2285);
PAINT MONO (-1910 2285);
FORCEPROP 0 LASTPIN (-1900 2325) $PN 169
J 2
(-1910 2335);
DISPLAY 0.680851 (-1910 2335);
PAINT MONO (-1910 2335);
FORCEPROP 0 LASTPIN (-1900 2375) $PN 171
J 2
(-1910 2385);
DISPLAY 0.680851 (-1910 2385);
PAINT MONO (-1910 2385);
FORCEPROP 0 LASTPIN (-1900 2425) $PN 173
J 2
(-1910 2435);
DISPLAY 0.680851 (-1910 2435);
PAINT MONO (-1910 2435);
FORCEPROP 0 LASTPIN (-1900 2475) $PN 175
J 2
(-1910 2485);
DISPLAY 0.680851 (-1910 2485);
PAINT MONO (-1910 2485);
FORCEPROP 0 LASTPIN (-1900 2525) $PN 177
J 2
(-1910 2535);
DISPLAY 0.680851 (-1910 2535);
PAINT MONO (-1910 2535);
FORCEPROP 0 LASTPIN (-1900 2575) $PN 180
J 2
(-1910 2585);
DISPLAY 0.680851 (-1910 2585);
PAINT MONO (-1910 2585);
FORCEPROP 0 LASTPIN (-1900 2625) $PN 182
J 2
(-1910 2635);
DISPLAY 0.680851 (-1910 2635);
PAINT MONO (-1910 2635);
FORCEPROP 0 LASTPIN (-1900 2675) $PN 184
J 2
(-1910 2685);
DISPLAY 0.680851 (-1910 2685);
PAINT MONO (-1910 2685);
FORCEPROP 0 LASTPIN (-1900 2725) $PN 186
J 2
(-1910 2735);
DISPLAY 0.680851 (-1910 2735);
PAINT MONO (-1910 2735);
FORCEPROP 0 LASTPIN (-1900 2775) $PN 188
J 2
(-1910 2785);
DISPLAY 0.680851 (-1910 2785);
PAINT MONO (-1910 2785);
FORCEPROP 0 LASTPIN (-1900 2825) $PN 191
J 2
(-1910 2835);
DISPLAY 0.680851 (-1910 2835);
PAINT MONO (-1910 2835);
FORCEPROP 0 LASTPIN (-1900 2875) $PN 193
J 2
(-1910 2885);
DISPLAY 0.680851 (-1910 2885);
PAINT MONO (-1910 2885);
FORCEPROP 0 LASTPIN (-1900 2925) $PN 195
J 2
(-1910 2935);
DISPLAY 0.680851 (-1910 2935);
PAINT MONO (-1910 2935);
FORCEPROP 0 LASTPIN (-1900 2975) $PN 197
J 2
(-1910 2985);
DISPLAY 0.680851 (-1910 2985);
PAINT MONO (-1910 2985);
FORCEPROP 0 LASTPIN (-1900 3025) $PN 199
J 2
(-1910 3035);
DISPLAY 0.680851 (-1910 3035);
PAINT MONO (-1910 3035);
FORCEPROP 0 LASTPIN (-1900 3075) $PN 202
J 2
(-1910 3085);
DISPLAY 0.680851 (-1910 3085);
PAINT MONO (-1910 3085);
FORCEPROP 0 LASTPIN (-1900 3125) $PN 204
J 2
(-1910 3135);
DISPLAY 0.680851 (-1910 3135);
PAINT MONO (-1910 3135);
FORCEPROP 0 LASTPIN (-1900 3175) $PN 206
J 2
(-1910 3185);
DISPLAY 0.680851 (-1910 3185);
PAINT MONO (-1910 3185);
FORCEPROP 0 LASTPIN (-1900 3225) $PN 208
J 2
(-1910 3235);
DISPLAY 0.680851 (-1910 3235);
PAINT MONO (-1910 3235);
FORCEPROP 0 LASTPIN (-1900 3275) $PN 210
J 2
(-1910 3285);
DISPLAY 0.680851 (-1910 3285);
PAINT MONO (-1910 3285);
FORCEPROP 0 LASTPIN (-1900 3325) $PN 212
J 2
(-1910 3335);
DISPLAY 0.680851 (-1910 3335);
PAINT MONO (-1910 3335);
FORCEPROP 0 LASTPIN (-1900 3375) $PN 214
J 2
(-1910 3385);
DISPLAY 0.680851 (-1910 3385);
PAINT MONO (-1910 3385);
FORCEPROP 0 LASTPIN (-1900 3425) $PN 216
J 2
(-1910 3435);
DISPLAY 0.680851 (-1910 3435);
PAINT MONO (-1910 3435);
FORCEPROP 0 LASTPIN (-1900 3475) $PN 219
J 2
(-1910 3485);
DISPLAY 0.680851 (-1910 3485);
PAINT MONO (-1910 3485);
FORCEPROP 0 LASTPIN (-1900 3525) $PN 222
J 2
(-1910 3535);
DISPLAY 0.680851 (-1910 3535);
PAINT MONO (-1910 3535);
FORCEPROP 0 LASTPIN (-1900 3575) $PN 224
J 2
(-1910 3585);
DISPLAY 0.680851 (-1910 3585);
PAINT MONO (-1910 3585);
FORCEPROP 0 LASTPIN (-1900 3625) $PN 226
J 2
(-1910 3635);
DISPLAY 0.680851 (-1910 3635);
PAINT MONO (-1910 3635);
FORCEPROP 0 LASTPIN (-1900 3675) $PN 228
J 2
(-1910 3685);
DISPLAY 0.680851 (-1910 3685);
PAINT MONO (-1910 3685);
FORCEPROP 0 LASTPIN (-1900 3725) $PN 230
J 2
(-1910 3735);
DISPLAY 0.680851 (-1910 3735);
PAINT MONO (-1910 3735);
FORCEPROP 0 LASTPIN (-1900 3775) $PN 233
J 2
(-1910 3785);
DISPLAY 0.680851 (-1910 3785);
PAINT MONO (-1910 3785);
FORCEPROP 0 LASTPIN (-1900 3825) $PN 235
J 2
(-1910 3835);
DISPLAY 0.680851 (-1910 3835);
PAINT MONO (-1910 3835);
FORCEPROP 0 LASTPIN (-1900 3875) $PN 237
J 2
(-1910 3885);
DISPLAY 0.680851 (-1910 3885);
PAINT MONO (-1910 3885);
FORCEPROP 0 LASTPIN (-1900 3925) $PN 240
J 2
(-1910 3935);
DISPLAY 0.680851 (-1910 3935);
PAINT MONO (-1910 3935);
FORCEPROP 0 LASTPIN (-1900 3975) $PN 242
J 2
(-1910 3985);
DISPLAY 0.680851 (-1910 3985);
PAINT MONO (-1910 3985);
FORCEPROP 0 LASTPIN (-1900 4025) $PN 244
J 2
(-1910 4035);
DISPLAY 0.680851 (-1910 4035);
PAINT MONO (-1910 4035);
FORCEPROP 0 LASTPIN (-1900 4075) $PN 246
J 2
(-1910 4085);
DISPLAY 0.680851 (-1910 4085);
PAINT MONO (-1910 4085);
FORCEPROP 0 LASTPIN (-1900 4125) $PN 248
J 2
(-1910 4135);
DISPLAY 0.680851 (-1910 4135);
PAINT MONO (-1910 4135);
FORCEPROP 0 LASTPIN (-1900 4175) $PN 251
J 2
(-1910 4185);
DISPLAY 0.680851 (-1910 4185);
PAINT MONO (-1910 4185);
FORCEPROP 0 LASTPIN (-1900 4225) $PN 253
J 2
(-1910 4235);
DISPLAY 0.680851 (-1910 4235);
PAINT MONO (-1910 4235);
FORCEPROP 0 LASTPIN (-1900 4275) $PN 255
J 2
(-1910 4285);
DISPLAY 0.680851 (-1910 4285);
PAINT MONO (-1910 4285);
FORCEPROP 0 LASTPIN (-1900 4325) $PN 257
J 2
(-1910 4335);
DISPLAY 0.680851 (-1910 4335);
PAINT MONO (-1910 4335);
FORCEPROP 0 LASTPIN (-1900 4375) $PN 259
J 2
(-1910 4385);
DISPLAY 0.680851 (-1910 4385);
PAINT MONO (-1910 4385);
FORCEPROP 0 LASTPIN (-1900 4425) $PN 262
J 2
(-1910 4435);
DISPLAY 0.680851 (-1910 4435);
PAINT MONO (-1910 4435);
FORCEPROP 0 LASTPIN (-1900 4475) $PN 264
J 2
(-1910 4485);
DISPLAY 0.680851 (-1910 4485);
PAINT MONO (-1910 4485);
FORCEPROP 0 LASTPIN (-1900 4525) $PN 266
J 2
(-1910 4535);
DISPLAY 0.680851 (-1910 4535);
PAINT MONO (-1910 4535);
FORCEPROP 0 LASTPIN (-1900 4575) $PN 268
J 2
(-1910 4585);
DISPLAY 0.680851 (-1910 4585);
PAINT MONO (-1910 4585);
FORCEPROP 0 LASTPIN (-1900 4625) $PN 270
J 2
(-1910 4635);
DISPLAY 0.680851 (-1910 4635);
PAINT MONO (-1910 4635);
FORCEPROP 0 LASTPIN (-1900 4675) $PN 273
J 2
(-1910 4685);
DISPLAY 0.680851 (-1910 4685);
PAINT MONO (-1910 4685);
FORCEPROP 0 LASTPIN (-1900 4725) $PN 275
J 2
(-1910 4735);
DISPLAY 0.680851 (-1910 4735);
PAINT MONO (-1910 4735);
FORCEPROP 0 LASTPIN (-1900 4775) $PN 277
J 2
(-1910 4785);
DISPLAY 0.680851 (-1910 4785);
PAINT MONO (-1910 4785);
FORCEPROP 0 LASTPIN (-1900 4825) $PN 279
J 2
(-1910 4835);
DISPLAY 0.680851 (-1910 4835);
PAINT MONO (-1910 4835);
FORCEPROP 0 LASTPIN (-1900 4875) $PN 281
J 2
(-1910 4885);
DISPLAY 0.680851 (-1910 4885);
PAINT MONO (-1910 4885);
FORCEPROP 0 LASTPIN (-1900 4925) $PN 284
J 2
(-1910 4935);
DISPLAY 0.680851 (-1910 4935);
PAINT MONO (-1910 4935);
FORCEPROP 0 LASTPIN (-1900 4975) $PN 286
J 2
(-1910 4985);
DISPLAY 0.680851 (-1910 4985);
PAINT MONO (-1910 4985);
FORCEPROP 0 LASTPIN (-1900 5025) $PN 288
J 2
(-1910 5035);
DISPLAY 0.680851 (-1910 5035);
PAINT MONO (-1910 5035);
FORCEPROP 2 LAST VALUE SCONN288_DDR506112002KQ
J 0
(-1750 5550);
DISPLAY 0.489362 (-1750 5550);
PAINT SKYBLUE (-1750 5550);
FORCEPROP 2 LAST PART_TYPE SMLF
J 0
(-1750 5600);
DISPLAY 1.021277 (-1750 5600);
FORCEPROP 1 LAST MATERIAL IO
J 0
(-1750 5350);
DISPLAY 0.468085 (-1750 5350);
PAINT SKYBLUE (-1750 5350);
FORCEPROP 1 LAST PART_NUMBER DFHST8FS479
J 0
(-1750 5425);
DISPLAY 0.468085 (-1750 5425);
PAINT SKYBLUE (-1750 5425);
FORCEPROP 1 LAST CDS_LMAN_SYM_OUTLINE -450,1800,450,-1750
J 0
(-1300 3525);
DISPLAY 0.468085 (-1300 3525);
PAINT GREEN (-1300 3525);
DISPLAY INVISIBLE (-1300 3525);
FORCEPROP 1 LAST PATH I140
J 0
(-1300 3525);
DISPLAY 0.723404 (-1300 3525);
PAINT GREEN (-1300 3525);
DISPLAY INVISIBLE (-1300 3525);
FORCEPROP 1 LAST NEEDS_NO_SIZE TRUE
J 0
(-1300 3525);
DISPLAY 0.723404 (-1300 3525);
PAINT GREEN (-1300 3525);
DISPLAY INVISIBLE (-1300 3525);
FORCEPROP 2 LAST CDS_LIB pure_quanta
J 0
(-1300 3525);
DISPLAY INVISIBLE (-1300 3525);
FORCEADD OFFPAGE..1
(-8325 3975);
FORCEPROP 2 LAST $XR0 21 
J 0
(-8546 3975);
DISPLAY 0.638298 (-8546 3975);
PAINT MONO (-8546 3975);
FORCEPROP 2 LAST CDS_LIB mstr_standard
J 0
(-8325 3975);
DISPLAY 0.723404 (-8325 3975);
PAINT MONO (-8325 3975);
DISPLAY INVISIBLE (-8325 3975);
FORCEPROP 1 LAST OFFPAGE TRUE
J 0
(-8000 3850);
DISPLAY 0.872340 (-8000 3850);
PAINT GREEN (-8000 3850);
DISPLAY INVISIBLE (-8000 3850);
FORCEPROP 1 LAST COMMENT_BODY TRUE
J 0
(-8200 3875);
DISPLAY 0.872340 (-8200 3875);
PAINT GREEN (-8200 3875);
DISPLAY INVISIBLE (-8200 3875);
FORCEPROP 2 LAST PATH I15
J 0
(-8275 4050);
DISPLAY 1.021277 (-8275 4050);
DISPLAY INVISIBLE (-8275 4050);
FORCEADD OFFPAGE..1
(-8325 4125);
FORCEPROP 2 LAST $XR0 21 
J 0
(-8546 4125);
DISPLAY 0.638298 (-8546 4125);
PAINT MONO (-8546 4125);
FORCEPROP 2 LAST CDS_LIB mstr_standard
J 0
(-8325 4125);
DISPLAY 0.723404 (-8325 4125);
PAINT MONO (-8325 4125);
DISPLAY INVISIBLE (-8325 4125);
FORCEPROP 1 LAST OFFPAGE TRUE
J 0
(-8000 4000);
DISPLAY 0.872340 (-8000 4000);
PAINT GREEN (-8000 4000);
DISPLAY INVISIBLE (-8000 4000);
FORCEPROP 1 LAST COMMENT_BODY TRUE
J 0
(-8200 4025);
DISPLAY 0.872340 (-8200 4025);
PAINT GREEN (-8200 4025);
DISPLAY INVISIBLE (-8200 4025);
FORCEPROP 2 LAST PATH I16
J 0
(-8275 4200);
DISPLAY 1.021277 (-8275 4200);
DISPLAY INVISIBLE (-8275 4200);
FORCEADD OFFPAGE..1
(-8325 4075);
FORCEPROP 2 LAST $XR0 21 
J 0
(-8546 4075);
DISPLAY 0.638298 (-8546 4075);
PAINT MONO (-8546 4075);
FORCEPROP 2 LAST CDS_LIB mstr_standard
J 0
(-8325 4075);
DISPLAY 0.808511 (-8325 4075);
DISPLAY INVISIBLE (-8325 4075);
FORCEPROP 1 LAST OFFPAGE TRUE
J 0
(-8000 3950);
DISPLAY 0.872340 (-8000 3950);
PAINT GREEN (-8000 3950);
DISPLAY INVISIBLE (-8000 3950);
FORCEPROP 1 LAST COMMENT_BODY TRUE
J 0
(-8200 3975);
DISPLAY 0.872340 (-8200 3975);
PAINT GREEN (-8200 3975);
DISPLAY INVISIBLE (-8200 3975);
FORCEPROP 2 LAST PATH I17
J 0
(-8275 4150);
DISPLAY 1.021277 (-8275 4150);
DISPLAY INVISIBLE (-8275 4150);
FORCEADD OFFPAGE..6
(-8325 2525);
FORCEPROP 2 LAST $XR5 136 
J 0
(-9054 2525);
DISPLAY 0.638298 (-9054 2525);
PAINT MONO (-9054 2525);
FORCEPROP 2 LAST $XR4 95 
J 0
(-8934 2525);
DISPLAY 0.638298 (-8934 2525);
PAINT MONO (-8934 2525);
FORCEPROP 2 LAST $XR3 94 
J 0
(-8844 2525);
DISPLAY 0.638298 (-8844 2525);
PAINT MONO (-8844 2525);
FORCEPROP 2 LAST $XR2 93 
J 0
(-8754 2525);
DISPLAY 0.638298 (-8754 2525);
PAINT MONO (-8754 2525);
FORCEPROP 2 LAST $XR1 92 
J 0
(-8664 2525);
DISPLAY 0.638298 (-8664 2525);
PAINT MONO (-8664 2525);
FORCEPROP 2 LAST $XR0 91 
J 0
(-8574 2525);
DISPLAY 0.638298 (-8574 2525);
PAINT MONO (-8574 2525);
FORCEPROP 2 LAST CDS_LIB mstr_standard
J 0
(-8325 2525);
DISPLAY 0.808511 (-8325 2525);
DISPLAY INVISIBLE (-8325 2525);
FORCEPROP 1 LAST OFFPAGE TRUE
J 0
(-8000 2400);
DISPLAY 0.872340 (-8000 2400);
PAINT GREEN (-8000 2400);
DISPLAY INVISIBLE (-8000 2400);
FORCEPROP 1 LAST COMMENT_BODY TRUE
J 0
(-8225 2450);
DISPLAY 0.872340 (-8225 2450);
PAINT GREEN (-8225 2450);
DISPLAY INVISIBLE (-8225 2450);
FORCEPROP 2 LAST PATH I179
J 0
(-8625 2575);
DISPLAY 1.021277 (-8625 2575);
DISPLAY INVISIBLE (-8625 2575);
FORCEADD OFFPAGE..1
(-8325 4275);
FORCEPROP 2 LAST $XR0 21 
J 0
(-8546 4275);
DISPLAY 0.638298 (-8546 4275);
PAINT MONO (-8546 4275);
FORCEPROP 2 LAST CDS_LIB mstr_standard
J 0
(-8325 4275);
DISPLAY 0.723404 (-8325 4275);
PAINT MONO (-8325 4275);
DISPLAY INVISIBLE (-8325 4275);
FORCEPROP 1 LAST OFFPAGE TRUE
J 0
(-8000 4150);
DISPLAY 0.872340 (-8000 4150);
PAINT GREEN (-8000 4150);
DISPLAY INVISIBLE (-8000 4150);
FORCEPROP 1 LAST COMMENT_BODY TRUE
J 0
(-8200 4175);
DISPLAY 0.872340 (-8200 4175);
PAINT GREEN (-8200 4175);
DISPLAY INVISIBLE (-8200 4175);
FORCEPROP 2 LAST PATH I18
J 0
(-8275 4350);
DISPLAY 1.021277 (-8275 4350);
DISPLAY INVISIBLE (-8275 4350);
FORCEADD Q_CAP..1
R 2
(-8600 2900);
FORCEPROP 1 LAST LOCATION C132
J 2
(-8650 3000);
DISPLAY 0.489362 (-8650 3000);
PAINT SKYBLUE (-8650 3000);
FORCEPROP 0 LAST $SEC 1
J 0
(-8650 3050);
DISPLAY 0.680851 (-8650 3050);
PAINT MONO (-8650 3050);
DISPLAY INVISIBLE (-8650 3050);
FORCEPROP 0 LAST CDS_SEC 1
J 0
(-8650 3050);
DISPLAY 1.021277 (-8650 3050);
DISPLAY INVISIBLE (-8650 3050);
FORCEPROP 1 LASTPIN (-8600 3000) $PN 1
J 2
(-8610 2980);
DISPLAY 0.489362 (-8610 2980);
PAINT MONO (-8610 2980);
FORCEPROP 1 LASTPIN (-8600 2800) $PN 2
J 2
(-8610 2780);
DISPLAY 0.489362 (-8610 2780);
PAINT MONO (-8610 2780);
FORCEPROP 1 LAST MATERIAL X7R
J 2
(-8650 2800);
DISPLAY 0.489362 (-8650 2800);
PAINT SKYBLUE (-8650 2800);
FORCEPROP 1 LAST TOLERANCE 10%
J 2
(-8650 2850);
DISPLAY 0.489362 (-8650 2850);
PAINT SKYBLUE (-8650 2850);
FORCEPROP 1 LAST VALUE 0.1UF
J 2
(-8650 2950);
DISPLAY 0.489362 (-8650 2950);
PAINT SKYBLUE (-8650 2950);
FORCEPROP 1 LAST VOLTAGE 25V
J 2
(-8650 2900);
DISPLAY 0.489362 (-8650 2900);
PAINT SKYBLUE (-8650 2900);
FORCEPROP 1 LAST PACK_TYPE 0402
J 2
(-8650 2700);
DISPLAY 0.489362 (-8650 2700);
PAINT SKYBLUE (-8650 2700);
FORCEPROP 1 LAST PART_NUMBER CH4104K1B00
J 2
(-8650 2750);
DISPLAY 0.489362 (-8650 2750);
PAINT SKYBLUE (-8650 2750);
FORCEPROP 2 LAST CDS_LIB pure_quanta
J 0
(-8600 2900);
DISPLAY INVISIBLE (-8600 2900);
FORCEPROP 0 LAST BOM_COST MEM
J 2
(-8655 3045);
DISPLAY 0.595745 (-8655 3045);
PAINT MONO (-8655 3045);
DISPLAY INVISIBLE (-8655 3045);
FORCEPROP 1 LAST PATH I185
J 2
(-8650 3050);
DISPLAY 0.978723 (-8650 3050);
PAINT WHITE (-8650 3050);
DISPLAY INVISIBLE (-8650 3050);
FORCEPROP 0 LAST ROOM MEM_CH_A_CPU0_DIMM1
J 2
(-8655 3045);
DISPLAY 0.595745 (-8655 3045);
PAINT RED (-8655 3045);
DISPLAY INVISIBLE (-8655 3045);
FORCEADD GND..1
(-8600 2675);
FORCEPROP 3 LASTPIN (-8600 2725) SIG_NAME GND\g
J 0
(-8590 2735);
DISPLAY 0.659574 (-8590 2735);
PAINT MONO (-8590 2735);
DISPLAY INVISIBLE (-8590 2735);
FORCEPROP 2 LAST CDS_LIB mstr_symbols
J 0
(-8600 2675);
DISPLAY 0.808511 (-8600 2675);
DISPLAY INVISIBLE (-8600 2675);
FORCEPROP 1 LAST SIZE 1B
J 0
(-8525 2625);
DISPLAY 0.723404 (-8525 2625);
PAINT GREEN (-8525 2625);
DISPLAY INVISIBLE (-8525 2625);
FORCEPROP 2 LAST BOM_COST MEM
J 0
(-8575 2800);
DISPLAY 0.659574 (-8575 2800);
DISPLAY INVISIBLE (-8575 2800);
FORCEPROP 1 LAST BODY_TYPE PLUMBING
J 0
(-8645 2632);
DISPLAY 0.276596 (-8645 2632);
PAINT GREEN (-8645 2632);
DISPLAY INVISIBLE (-8645 2632);
FORCEPROP 1 LAST PATH I186
J 0
(-8525 2675);
DISPLAY 0.872340 (-8525 2675);
PAINT AQUA (-8525 2675);
DISPLAY INVISIBLE (-8525 2675);
FORCEPROP 1 LAST VOLTAGE 0
J 0
(-8620 2770);
DISPLAY 0.829787 (-8620 2770);
PAINT SKYBLUE (-8620 2770);
DISPLAY INVISIBLE (-8620 2770);
FORCEPROP 2 LAST ROOM MEM_EFGH_DECOUPLING_CAPS
J 0
(-8575 2750);
DISPLAY 0.659574 (-8575 2750);
PAINT RED (-8575 2750);
DISPLAY INVISIBLE (-8575 2750);
FORCEPROP 1 LAST HDL_POWER GND
J 0
(-8600 2825);
DISPLAY 0.723404 (-8600 2825);
PAINT GREEN (-8600 2825);
DISPLAY INVISIBLE (-8600 2825);
FORCEADD OFFPAGE..6
(-9000 1825);
FORCEPROP 2 LAST $XR5 81 
J 0
(-9429 1789);
DISPLAY 0.638298 (-9429 1789);
PAINT MONO (-9429 1789);
FORCEPROP 2 LAST $XR4 95 
J 0
(-9339 1789);
DISPLAY 0.638298 (-9339 1789);
PAINT MONO (-9339 1789);
FORCEPROP 2 LAST $XR3 94 
J 0
(-9249 1789);
DISPLAY 0.638298 (-9249 1789);
PAINT MONO (-9249 1789);
FORCEPROP 2 LAST $XR2 93 
J 0
(-9429 1825);
DISPLAY 0.638298 (-9429 1825);
PAINT MONO (-9429 1825);
FORCEPROP 2 LAST $XR1 92 
J 0
(-9339 1825);
DISPLAY 0.638298 (-9339 1825);
PAINT MONO (-9339 1825);
FORCEPROP 2 LAST $XR0 91 
J 0
(-9249 1825);
DISPLAY 0.638298 (-9249 1825);
PAINT MONO (-9249 1825);
FORCEPROP 2 LAST CDS_LIB mstr_standard
J 0
(-9000 1825);
DISPLAY INVISIBLE (-9000 1825);
FORCEPROP 1 LAST OFFPAGE TRUE
J 0
(-8675 1700);
DISPLAY 0.872340 (-8675 1700);
PAINT GREEN (-8675 1700);
DISPLAY INVISIBLE (-8675 1700);
FORCEPROP 1 LAST COMMENT_BODY TRUE
J 0
(-8900 1750);
DISPLAY 0.872340 (-8900 1750);
PAINT GREEN (-8900 1750);
DISPLAY INVISIBLE (-8900 1750);
FORCEPROP 2 LAST PATH I187
J 0
(-8950 1900);
DISPLAY 1.021277 (-8950 1900);
DISPLAY INVISIBLE (-8950 1900);
FORCEADD Q_RES..1
R 2
(-8475 1825);
FORCEPROP 1 LAST LOCATION R302
J 2
(-8425 1875);
DISPLAY 0.489362 (-8425 1875);
PAINT SKYBLUE (-8425 1875);
FORCEPROP 0 LAST $SEC 1
J 0
(-8425 1925);
DISPLAY 0.680851 (-8425 1925);
PAINT MONO (-8425 1925);
DISPLAY INVISIBLE (-8425 1925);
FORCEPROP 0 LAST CDS_SEC 1
J 0
(-8425 1925);
DISPLAY 1.021277 (-8425 1925);
DISPLAY INVISIBLE (-8425 1925);
FORCEPROP 1 LASTPIN (-8375 1825) $PN 1
J 2
(-8387 1837);
DISPLAY 0.489362 (-8387 1837);
PAINT MONO (-8387 1837);
FORCEPROP 1 LASTPIN (-8575 1825) $PN 2
J 2
(-8537 1837);
DISPLAY 0.489362 (-8537 1837);
PAINT MONO (-8537 1837);
FORCEPROP 1 LAST VALUE 0
J 0
(-8475 1775);
DISPLAY 0.489362 (-8475 1775);
PAINT SKYBLUE (-8475 1775);
FORCEPROP 2 LAST CDS_LIB pure_quanta
J 0
(-8475 1825);
DISPLAY INVISIBLE (-8475 1825);
FORCEPROP 2 LAST BOM_COST MEM
J 0
(-8500 1975);
DISPLAY 0.744681 (-8500 1975);
PAINT WHITE (-8500 1975);
DISPLAY INVISIBLE (-8500 1975);
FORCEPROP 1 LAST PATH I188
J 2
(-8425 1975);
DISPLAY 0.978723 (-8425 1975);
PAINT WHITE (-8425 1975);
DISPLAY INVISIBLE (-8425 1975);
FORCEPROP 1 LAST WATTAGE 1/16W
J 0
(-8400 1750);
DISPLAY 0.489362 (-8400 1750);
PAINT SKYBLUE (-8400 1750);
DISPLAY INVISIBLE (-8400 1750);
FORCEPROP 1 LAST MATERIAL CHIP
J 0
(-8650 1800);
DISPLAY 0.489362 (-8650 1800);
PAINT SKYBLUE (-8650 1800);
DISPLAY INVISIBLE (-8650 1800);
FORCEPROP 1 LAST TOLERANCE 5%
J 2
(-8350 1800);
DISPLAY 0.489362 (-8350 1800);
PAINT SKYBLUE (-8350 1800);
DISPLAY INVISIBLE (-8350 1800);
FORCEPROP 1 LAST PART_NUMBER CS00002JB38
J 0
(-8575 1875);
DISPLAY 0.489362 (-8575 1875);
PAINT SKYBLUE (-8575 1875);
DISPLAY INVISIBLE (-8575 1875);
FORCEPROP 1 LAST PACK_TYPE 0402LF
J 0
(-8650 1750);
DISPLAY 0.489362 (-8650 1750);
PAINT SKYBLUE (-8650 1750);
DISPLAY INVISIBLE (-8650 1750);
FORCEPROP 2 LAST ROOM RST_CPU0_PLD_TO_DIMM
J 0
(-8500 1925);
DISPLAY 0.744681 (-8500 1925);
PAINT RED (-8500 1925);
DISPLAY INVISIBLE (-8500 1925);
FORCEADD Q_RES..2
(-8350 1975);
FORCEPROP 1 LAST LOCATION R101
J 0
(-8305 2100);
DISPLAY 0.489362 (-8305 2100);
PAINT SKYBLUE (-8305 2100);
FORCEPROP 0 LAST $SEC 1
J 0
(-8300 2150);
DISPLAY 0.680851 (-8300 2150);
PAINT MONO (-8300 2150);
DISPLAY INVISIBLE (-8300 2150);
FORCEPROP 0 LAST CDS_SEC 1
J 0
(-8300 2150);
DISPLAY 1.021277 (-8300 2150);
DISPLAY INVISIBLE (-8300 2150);
FORCEPROP 1 LASTPIN (-8350 2075) $PN 1
J 0
(-8345 2037);
DISPLAY 0.489362 (-8345 2037);
PAINT MONO (-8345 2037);
FORCEPROP 1 LASTPIN (-8350 1875) $PN 2
J 0
(-8345 1885);
DISPLAY 0.489362 (-8345 1885);
PAINT MONO (-8345 1885);
FORCEPROP 1 LAST WATTAGE 1/16W
J 0
(-8300 2000);
DISPLAY 0.489362 (-8300 2000);
PAINT SKYBLUE (-8300 2000);
FORCEPROP 1 LAST MATERIAL EMPTY
J 0
(-8300 1975);
DISPLAY 0.489362 (-8300 1975);
PAINT RED (-8300 1975);
FORCEPROP 1 LAST TOLERANCE 5%
J 0
(-8300 2025);
DISPLAY 0.489362 (-8300 2025);
PAINT SKYBLUE (-8300 2025);
FORCEPROP 1 LAST VALUE 1K
J 0
(-8305 2050);
DISPLAY 0.489362 (-8305 2050);
PAINT SKYBLUE (-8305 2050);
FORCEPROP 1 LAST PACK_TYPE 0402LF
J 0
(-8300 1925);
DISPLAY 0.489362 (-8300 1925);
PAINT SKYBLUE (-8300 1925);
FORCEPROP 2 LAST CDS_LIB pure_quanta
J 0
(-8350 1975);
DISPLAY INVISIBLE (-8350 1975);
FORCEPROP 2 LAST BOM_COST MEM
J 0
(-8300 2150);
DISPLAY 0.808511 (-8300 2150);
DISPLAY INVISIBLE (-8300 2150);
FORCEPROP 1 LAST PATH I189
J 0
(-8300 2150);
DISPLAY 0.978723 (-8300 2150);
PAINT WHITE (-8300 2150);
DISPLAY INVISIBLE (-8300 2150);
FORCEPROP 1 LAST PART_NUMBER TMP_QCS21002JB34
J 0
(-8300 1950);
DISPLAY 0.489362 (-8300 1950);
PAINT SKYBLUE (-8300 1950);
DISPLAY INVISIBLE (-8300 1950);
FORCEPROP 2 LAST ROOM MEM_CH_A_CPU0_DIMM1
J 0
(-8300 2200);
DISPLAY 0.808511 (-8300 2200);
PAINT RED (-8300 2200);
DISPLAY INVISIBLE (-8300 2200);
FORCEADD OFFPAGE..1
(-8325 4225);
FORCEPROP 2 LAST $XR0 21 
J 0
(-8546 4225);
DISPLAY 0.638298 (-8546 4225);
PAINT MONO (-8546 4225);
FORCEPROP 2 LAST CDS_LIB mstr_standard
J 0
(-8325 4225);
DISPLAY 0.808511 (-8325 4225);
DISPLAY INVISIBLE (-8325 4225);
FORCEPROP 1 LAST OFFPAGE TRUE
J 0
(-8000 4100);
DISPLAY 0.872340 (-8000 4100);
PAINT GREEN (-8000 4100);
DISPLAY INVISIBLE (-8000 4100);
FORCEPROP 1 LAST COMMENT_BODY TRUE
J 0
(-8200 4125);
DISPLAY 0.872340 (-8200 4125);
PAINT GREEN (-8200 4125);
DISPLAY INVISIBLE (-8200 4125);
FORCEPROP 2 LAST PATH I19
J 0
(-8275 4300);
DISPLAY 1.021277 (-8275 4300);
DISPLAY INVISIBLE (-8275 4300);
FORCEADD VCC_CORE..1
(-8350 2150);
FORCEPROP 3 LASTPIN (-8350 2100) SIG_NAME P3V3_STBY\g
J 0
(-8340 2110);
DISPLAY 0.659574 (-8340 2110);
PAINT MONO (-8340 2110);
DISPLAY INVISIBLE (-8340 2110);
FORCEPROP 1 LAST HDL_POWER P3V3_STBY
J 1
(-8350 2200);
DISPLAY 0.489362 (-8350 2200);
PAINT GREEN (-8350 2200);
FORCEPROP 2 LAST CDS_LIB mstr_symbols
J 0
(-8350 2150);
DISPLAY INVISIBLE (-8350 2150);
FORCEPROP 1 LAST PATH I190
J 0
(-8300 2175);
DISPLAY 0.872340 (-8300 2175);
PAINT AQUA (-8300 2175);
DISPLAY INVISIBLE (-8300 2175);
FORCEPROP 0 LAST VOLTAGE 3.3
J 0
(-8625 2300);
DISPLAY 1.021277 (-8625 2300);
PAINT SKYBLUE (-8625 2300);
DISPLAY INVISIBLE (-8625 2300);
FORCEPROP 2 LAST ROOM PVCCINFAON_CPU0_CTRL
J 0
(-8350 2250);
DISPLAY 0.808511 (-8350 2250);
PAINT RED (-8350 2250);
DISPLAY INVISIBLE (-8350 2250);
FORCEADD OFFPAGE..2
(-2500 4350);
FORCEPROP 2 LAST $XR0 21 
J 0
(-2311 4350);
DISPLAY 0.638298 (-2311 4350);
PAINT MONO (-2311 4350);
FORCEPROP 2 LAST PATH I192
J 0
(-2300 4400);
DISPLAY 0.680851 (-2300 4400);
DISPLAY INVISIBLE (-2300 4400);
FORCEPROP 2 LAST CDS_LIB mstr_standard
J 0
(-2500 4350);
DISPLAY 0.723404 (-2500 4350);
PAINT MONO (-2500 4350);
DISPLAY INVISIBLE (-2500 4350);
FORCEPROP 1 LAST OFFPAGE TRUE
J 0
(-2175 4225);
DISPLAY 0.723404 (-2175 4225);
PAINT GREEN (-2175 4225);
DISPLAY INVISIBLE (-2175 4225);
FORCEPROP 1 LAST COMMENT_BODY TRUE
J 0
(-2545 4255);
DISPLAY 0.872340 (-2545 4255);
PAINT GREEN (-2545 4255);
DISPLAY INVISIBLE (-2545 4255);
FORCEADD OFFPAGE..2
(-2500 4300);
FORCEPROP 2 LAST $XR0 21 
J 0
(-2311 4300);
DISPLAY 0.638298 (-2311 4300);
PAINT MONO (-2311 4300);
FORCEPROP 2 LAST PATH I193
J 0
(-2300 4350);
DISPLAY 0.680851 (-2300 4350);
DISPLAY INVISIBLE (-2300 4350);
FORCEPROP 2 LAST CDS_LIB mstr_standard
J 0
(-2500 4300);
DISPLAY 0.723404 (-2500 4300);
PAINT MONO (-2500 4300);
DISPLAY INVISIBLE (-2500 4300);
FORCEPROP 1 LAST OFFPAGE TRUE
J 0
(-2175 4175);
DISPLAY 0.723404 (-2175 4175);
PAINT GREEN (-2175 4175);
DISPLAY INVISIBLE (-2175 4175);
FORCEPROP 1 LAST COMMENT_BODY TRUE
J 0
(-2545 4205);
DISPLAY 0.872340 (-2545 4205);
PAINT GREEN (-2545 4205);
DISPLAY INVISIBLE (-2545 4205);
FORCEADD TAP..1
(-3300 4250);
FORCEPROP 3 LASTPIN (-3350 4250) SIG_NAME M_L_CPU0_SA_DQS_DN<9>
J 0
(-3340 4260);
DISPLAY 0.659574 (-3340 4260);
PAINT MONO (-3340 4260);
DISPLAY INVISIBLE (-3340 4260);
FORCEPROP 1 LASTPIN (-3350 4250) BN 9
J 0
(-3362 4258);
DISPLAY 0.489362 (-3362 4258);
PAINT GREEN (-3362 4258);
FORCEPROP 2 LAST CDS_LIB mstr_standard
J 0
(-3300 4250);
DISPLAY 0.723404 (-3300 4250);
PAINT MONO (-3300 4250);
DISPLAY INVISIBLE (-3300 4250);
FORCEPROP 1 LAST BODY_TYPE PLUMBING
J 0
(-3300 4300);
DISPLAY 0.872340 (-3300 4300);
PAINT GREEN (-3300 4300);
DISPLAY INVISIBLE (-3300 4300);
FORCEPROP 1 LAST HDL_TAP TRUE
J 0
(-2975 4125);
DISPLAY 0.872340 (-2975 4125);
DISPLAY INVISIBLE (-2975 4125);
FORCEPROP 1 LAST PATH I194
J 0
(-3302 4250);
DISPLAY 0.872340 (-3302 4250);
PAINT GREEN (-3302 4250);
DISPLAY INVISIBLE (-3302 4250);
FORCEADD TAP..1
(-3500 4200);
FORCEPROP 3 LASTPIN (-3550 4200) SIG_NAME M_L_CPU0_SA_DQS_DP<8>
J 0
(-3540 4210);
DISPLAY 0.659574 (-3540 4210);
PAINT MONO (-3540 4210);
DISPLAY INVISIBLE (-3540 4210);
FORCEPROP 1 LASTPIN (-3550 4200) BN 8
J 0
(-3562 4208);
DISPLAY 0.489362 (-3562 4208);
PAINT GREEN (-3562 4208);
FORCEPROP 2 LAST CDS_LIB mstr_standard
J 0
(-3500 4200);
DISPLAY 0.723404 (-3500 4200);
PAINT MONO (-3500 4200);
DISPLAY INVISIBLE (-3500 4200);
FORCEPROP 1 LAST BODY_TYPE PLUMBING
J 0
(-3500 4250);
DISPLAY 0.872340 (-3500 4250);
PAINT GREEN (-3500 4250);
DISPLAY INVISIBLE (-3500 4250);
FORCEPROP 1 LAST HDL_TAP TRUE
J 0
(-3175 4075);
DISPLAY 0.872340 (-3175 4075);
DISPLAY INVISIBLE (-3175 4075);
FORCEPROP 1 LAST PATH I195
J 0
(-3502 4200);
DISPLAY 0.872340 (-3502 4200);
PAINT GREEN (-3502 4200);
DISPLAY INVISIBLE (-3502 4200);
FORCEADD TAP..1
(-3500 4300);
FORCEPROP 3 LASTPIN (-3550 4300) SIG_NAME M_L_CPU0_SA_DQS_DP<9>
J 0
(-3540 4310);
DISPLAY 0.659574 (-3540 4310);
PAINT MONO (-3540 4310);
DISPLAY INVISIBLE (-3540 4310);
FORCEPROP 1 LASTPIN (-3550 4300) BN 9
J 0
(-3562 4308);
DISPLAY 0.489362 (-3562 4308);
PAINT GREEN (-3562 4308);
FORCEPROP 2 LAST CDS_LIB mstr_standard
J 0
(-3500 4300);
DISPLAY 0.723404 (-3500 4300);
PAINT MONO (-3500 4300);
DISPLAY INVISIBLE (-3500 4300);
FORCEPROP 1 LAST BODY_TYPE PLUMBING
J 0
(-3500 4350);
DISPLAY 0.872340 (-3500 4350);
PAINT GREEN (-3500 4350);
DISPLAY INVISIBLE (-3500 4350);
FORCEPROP 1 LAST HDL_TAP TRUE
J 0
(-3175 4175);
DISPLAY 0.872340 (-3175 4175);
DISPLAY INVISIBLE (-3175 4175);
FORCEPROP 1 LAST PATH I196
J 0
(-3502 4300);
DISPLAY 0.872340 (-3502 4300);
PAINT GREEN (-3502 4300);
DISPLAY INVISIBLE (-3502 4300);
FORCEADD TAP..1
(-3300 4150);
FORCEPROP 3 LASTPIN (-3350 4150) SIG_NAME M_L_CPU0_SA_DQS_DN<8>
J 0
(-3340 4160);
DISPLAY 0.659574 (-3340 4160);
PAINT MONO (-3340 4160);
DISPLAY INVISIBLE (-3340 4160);
FORCEPROP 1 LASTPIN (-3350 4150) BN 8
J 0
(-3362 4158);
DISPLAY 0.489362 (-3362 4158);
PAINT GREEN (-3362 4158);
FORCEPROP 2 LAST CDS_LIB mstr_standard
J 0
(-3300 4150);
DISPLAY 0.723404 (-3300 4150);
PAINT MONO (-3300 4150);
DISPLAY INVISIBLE (-3300 4150);
FORCEPROP 1 LAST BODY_TYPE PLUMBING
J 0
(-3300 4200);
DISPLAY 0.872340 (-3300 4200);
PAINT GREEN (-3300 4200);
DISPLAY INVISIBLE (-3300 4200);
FORCEPROP 1 LAST HDL_TAP TRUE
J 0
(-2975 4025);
DISPLAY 0.872340 (-2975 4025);
DISPLAY INVISIBLE (-2975 4025);
FORCEPROP 1 LAST PATH I197
J 0
(-3302 4150);
DISPLAY 0.872340 (-3302 4150);
PAINT GREEN (-3302 4150);
DISPLAY INVISIBLE (-3302 4150);
FORCEADD TAP..1
(-3300 4050);
FORCEPROP 3 LASTPIN (-3350 4050) SIG_NAME M_L_CPU0_SA_DQS_DN<7>
J 0
(-3340 4060);
DISPLAY 0.659574 (-3340 4060);
PAINT MONO (-3340 4060);
DISPLAY INVISIBLE (-3340 4060);
FORCEPROP 1 LASTPIN (-3350 4050) BN 7
J 0
(-3362 4058);
DISPLAY 0.489362 (-3362 4058);
PAINT GREEN (-3362 4058);
FORCEPROP 2 LAST CDS_LIB mstr_standard
J 0
(-3300 4050);
DISPLAY 0.723404 (-3300 4050);
PAINT MONO (-3300 4050);
DISPLAY INVISIBLE (-3300 4050);
FORCEPROP 1 LAST BODY_TYPE PLUMBING
J 0
(-3300 4100);
DISPLAY 0.872340 (-3300 4100);
PAINT GREEN (-3300 4100);
DISPLAY INVISIBLE (-3300 4100);
FORCEPROP 1 LAST HDL_TAP TRUE
J 0
(-2975 3925);
DISPLAY 0.872340 (-2975 3925);
DISPLAY INVISIBLE (-2975 3925);
FORCEPROP 1 LAST PATH I198
J 0
(-3302 4050);
DISPLAY 0.872340 (-3302 4050);
PAINT GREEN (-3302 4050);
DISPLAY INVISIBLE (-3302 4050);
FORCEADD TAP..1
(-3300 3950);
FORCEPROP 3 LASTPIN (-3350 3950) SIG_NAME M_L_CPU0_SA_DQS_DN<6>
J 0
(-3340 3960);
DISPLAY 0.659574 (-3340 3960);
PAINT MONO (-3340 3960);
DISPLAY INVISIBLE (-3340 3960);
FORCEPROP 1 LASTPIN (-3350 3950) BN 6
J 0
(-3362 3958);
DISPLAY 0.489362 (-3362 3958);
PAINT GREEN (-3362 3958);
FORCEPROP 2 LAST CDS_LIB mstr_standard
J 0
(-3300 3950);
DISPLAY 0.723404 (-3300 3950);
PAINT MONO (-3300 3950);
DISPLAY INVISIBLE (-3300 3950);
FORCEPROP 1 LAST BODY_TYPE PLUMBING
J 0
(-3300 4000);
DISPLAY 0.872340 (-3300 4000);
PAINT GREEN (-3300 4000);
DISPLAY INVISIBLE (-3300 4000);
FORCEPROP 1 LAST HDL_TAP TRUE
J 0
(-2975 3825);
DISPLAY 0.872340 (-2975 3825);
DISPLAY INVISIBLE (-2975 3825);
FORCEPROP 1 LAST PATH I199
J 0
(-3302 3950);
DISPLAY 0.872340 (-3302 3950);
PAINT GREEN (-3302 3950);
DISPLAY INVISIBLE (-3302 3950);
FORCEADD OFFPAGE..5
(-8325 1675);
FORCEPROP 2 LAST $XR0 21 
J 0
(-8549 1675);
DISPLAY 0.638298 (-8549 1675);
PAINT MONO (-8549 1675);
FORCEPROP 2 LAST CDS_LIB mstr_standard
J 0
(-8325 1675);
DISPLAY 0.808511 (-8325 1675);
DISPLAY INVISIBLE (-8325 1675);
FORCEPROP 1 LAST OFFPAGE TRUE
J 0
(-8000 1550);
DISPLAY 0.872340 (-8000 1550);
PAINT GREEN (-8000 1550);
DISPLAY INVISIBLE (-8000 1550);
FORCEPROP 1 LAST COMMENT_BODY TRUE
J 0
(-8225 1600);
DISPLAY 0.872340 (-8225 1600);
PAINT GREEN (-8225 1600);
DISPLAY INVISIBLE (-8225 1600);
FORCEPROP 2 LAST PATH I2
J 0
(-8275 1750);
DISPLAY 1.021277 (-8275 1750);
DISPLAY INVISIBLE (-8275 1750);
FORCEADD OFFPAGE..1
(-8325 5125);
FORCEPROP 2 LAST $XR0 21 
J 0
(-8546 5125);
DISPLAY 0.638298 (-8546 5125);
PAINT MONO (-8546 5125);
FORCEPROP 2 LAST CDS_LIB mstr_standard
J 0
(-8325 5125);
DISPLAY 0.723404 (-8325 5125);
PAINT MONO (-8325 5125);
DISPLAY INVISIBLE (-8325 5125);
FORCEPROP 1 LAST OFFPAGE TRUE
J 0
(-8000 5000);
DISPLAY 0.872340 (-8000 5000);
PAINT GREEN (-8000 5000);
DISPLAY INVISIBLE (-8000 5000);
FORCEPROP 1 LAST COMMENT_BODY TRUE
J 0
(-8200 5025);
DISPLAY 0.872340 (-8200 5025);
PAINT GREEN (-8200 5025);
DISPLAY INVISIBLE (-8200 5025);
FORCEPROP 2 LAST PATH I20
J 0
(-8275 5200);
DISPLAY 1.021277 (-8275 5200);
DISPLAY INVISIBLE (-8275 5200);
FORCEADD TAP..1
(-3500 4100);
FORCEPROP 3 LASTPIN (-3550 4100) SIG_NAME M_L_CPU0_SA_DQS_DP<7>
J 0
(-3540 4110);
DISPLAY 0.659574 (-3540 4110);
PAINT MONO (-3540 4110);
DISPLAY INVISIBLE (-3540 4110);
FORCEPROP 1 LASTPIN (-3550 4100) BN 7
J 0
(-3562 4108);
DISPLAY 0.489362 (-3562 4108);
PAINT GREEN (-3562 4108);
FORCEPROP 2 LAST CDS_LIB mstr_standard
J 0
(-3500 4100);
DISPLAY 0.723404 (-3500 4100);
PAINT MONO (-3500 4100);
DISPLAY INVISIBLE (-3500 4100);
FORCEPROP 1 LAST BODY_TYPE PLUMBING
J 0
(-3500 4150);
DISPLAY 0.872340 (-3500 4150);
PAINT GREEN (-3500 4150);
DISPLAY INVISIBLE (-3500 4150);
FORCEPROP 1 LAST HDL_TAP TRUE
J 0
(-3175 3975);
DISPLAY 0.872340 (-3175 3975);
DISPLAY INVISIBLE (-3175 3975);
FORCEPROP 1 LAST PATH I200
J 0
(-3502 4100);
DISPLAY 0.872340 (-3502 4100);
PAINT GREEN (-3502 4100);
DISPLAY INVISIBLE (-3502 4100);
FORCEADD TAP..1
(-3500 4000);
FORCEPROP 3 LASTPIN (-3550 4000) SIG_NAME M_L_CPU0_SA_DQS_DP<6>
J 0
(-3540 4010);
DISPLAY 0.659574 (-3540 4010);
PAINT MONO (-3540 4010);
DISPLAY INVISIBLE (-3540 4010);
FORCEPROP 1 LASTPIN (-3550 4000) BN 6
J 0
(-3562 4008);
DISPLAY 0.489362 (-3562 4008);
PAINT GREEN (-3562 4008);
FORCEPROP 2 LAST CDS_LIB mstr_standard
J 0
(-3500 4000);
DISPLAY 0.723404 (-3500 4000);
PAINT MONO (-3500 4000);
DISPLAY INVISIBLE (-3500 4000);
FORCEPROP 1 LAST BODY_TYPE PLUMBING
J 0
(-3500 4050);
DISPLAY 0.872340 (-3500 4050);
PAINT GREEN (-3500 4050);
DISPLAY INVISIBLE (-3500 4050);
FORCEPROP 1 LAST HDL_TAP TRUE
J 0
(-3175 3875);
DISPLAY 0.872340 (-3175 3875);
DISPLAY INVISIBLE (-3175 3875);
FORCEPROP 1 LAST PATH I201
J 0
(-3502 4000);
DISPLAY 0.872340 (-3502 4000);
PAINT GREEN (-3502 4000);
DISPLAY INVISIBLE (-3502 4000);
FORCEADD TAP..1
(-3300 3750);
FORCEPROP 3 LASTPIN (-3350 3750) SIG_NAME M_L_CPU0_SA_DQS_DN<4>
J 0
(-3340 3760);
DISPLAY 0.659574 (-3340 3760);
PAINT MONO (-3340 3760);
DISPLAY INVISIBLE (-3340 3760);
FORCEPROP 1 LASTPIN (-3350 3750) BN 4
J 0
(-3362 3758);
DISPLAY 0.489362 (-3362 3758);
PAINT GREEN (-3362 3758);
FORCEPROP 2 LAST CDS_LIB mstr_standard
J 0
(-3300 3750);
DISPLAY 0.723404 (-3300 3750);
PAINT MONO (-3300 3750);
DISPLAY INVISIBLE (-3300 3750);
FORCEPROP 1 LAST BODY_TYPE PLUMBING
J 0
(-3300 3800);
DISPLAY 0.872340 (-3300 3800);
PAINT GREEN (-3300 3800);
DISPLAY INVISIBLE (-3300 3800);
FORCEPROP 1 LAST HDL_TAP TRUE
J 0
(-2975 3625);
DISPLAY 0.872340 (-2975 3625);
DISPLAY INVISIBLE (-2975 3625);
FORCEPROP 1 LAST PATH I202
J 0
(-3302 3750);
DISPLAY 0.872340 (-3302 3750);
PAINT GREEN (-3302 3750);
DISPLAY INVISIBLE (-3302 3750);
FORCEADD TAP..1
(-3300 3850);
FORCEPROP 3 LASTPIN (-3350 3850) SIG_NAME M_L_CPU0_SA_DQS_DN<5>
J 0
(-3340 3860);
DISPLAY 0.659574 (-3340 3860);
PAINT MONO (-3340 3860);
DISPLAY INVISIBLE (-3340 3860);
FORCEPROP 1 LASTPIN (-3350 3850) BN 5
J 0
(-3362 3858);
DISPLAY 0.489362 (-3362 3858);
PAINT GREEN (-3362 3858);
FORCEPROP 2 LAST CDS_LIB mstr_standard
J 0
(-3300 3850);
DISPLAY 0.723404 (-3300 3850);
PAINT MONO (-3300 3850);
DISPLAY INVISIBLE (-3300 3850);
FORCEPROP 1 LAST BODY_TYPE PLUMBING
J 0
(-3300 3900);
DISPLAY 0.872340 (-3300 3900);
PAINT GREEN (-3300 3900);
DISPLAY INVISIBLE (-3300 3900);
FORCEPROP 1 LAST HDL_TAP TRUE
J 0
(-2975 3725);
DISPLAY 0.872340 (-2975 3725);
DISPLAY INVISIBLE (-2975 3725);
FORCEPROP 1 LAST PATH I203
J 0
(-3302 3850);
DISPLAY 0.872340 (-3302 3850);
PAINT GREEN (-3302 3850);
DISPLAY INVISIBLE (-3302 3850);
FORCEADD TAP..1
(-3500 3900);
FORCEPROP 3 LASTPIN (-3550 3900) SIG_NAME M_L_CPU0_SA_DQS_DP<5>
J 0
(-3540 3910);
DISPLAY 0.659574 (-3540 3910);
PAINT MONO (-3540 3910);
DISPLAY INVISIBLE (-3540 3910);
FORCEPROP 1 LASTPIN (-3550 3900) BN 5
J 0
(-3562 3908);
DISPLAY 0.489362 (-3562 3908);
PAINT GREEN (-3562 3908);
FORCEPROP 2 LAST CDS_LIB mstr_standard
J 0
(-3500 3900);
DISPLAY 0.723404 (-3500 3900);
PAINT MONO (-3500 3900);
DISPLAY INVISIBLE (-3500 3900);
FORCEPROP 1 LAST BODY_TYPE PLUMBING
J 0
(-3500 3950);
DISPLAY 0.872340 (-3500 3950);
PAINT GREEN (-3500 3950);
DISPLAY INVISIBLE (-3500 3950);
FORCEPROP 1 LAST HDL_TAP TRUE
J 0
(-3175 3775);
DISPLAY 0.872340 (-3175 3775);
DISPLAY INVISIBLE (-3175 3775);
FORCEPROP 1 LAST PATH I204
J 0
(-3502 3900);
DISPLAY 0.872340 (-3502 3900);
PAINT GREEN (-3502 3900);
DISPLAY INVISIBLE (-3502 3900);
FORCEADD TAP..1
(-3500 3700);
FORCEPROP 3 LASTPIN (-3550 3700) SIG_NAME M_L_CPU0_SA_DQS_DP<3>
J 0
(-3540 3710);
DISPLAY 0.659574 (-3540 3710);
PAINT MONO (-3540 3710);
DISPLAY INVISIBLE (-3540 3710);
FORCEPROP 1 LASTPIN (-3550 3700) BN 3
J 0
(-3562 3708);
DISPLAY 0.489362 (-3562 3708);
PAINT GREEN (-3562 3708);
FORCEPROP 2 LAST CDS_LIB mstr_standard
J 0
(-3500 3700);
DISPLAY 0.723404 (-3500 3700);
PAINT MONO (-3500 3700);
DISPLAY INVISIBLE (-3500 3700);
FORCEPROP 1 LAST BODY_TYPE PLUMBING
J 0
(-3500 3750);
DISPLAY 0.872340 (-3500 3750);
PAINT GREEN (-3500 3750);
DISPLAY INVISIBLE (-3500 3750);
FORCEPROP 1 LAST HDL_TAP TRUE
J 0
(-3175 3575);
DISPLAY 0.872340 (-3175 3575);
DISPLAY INVISIBLE (-3175 3575);
FORCEPROP 1 LAST PATH I205
J 0
(-3502 3700);
DISPLAY 0.872340 (-3502 3700);
PAINT GREEN (-3502 3700);
DISPLAY INVISIBLE (-3502 3700);
FORCEADD TAP..1
(-3500 3800);
FORCEPROP 3 LASTPIN (-3550 3800) SIG_NAME M_L_CPU0_SA_DQS_DP<4>
J 0
(-3540 3810);
DISPLAY 0.659574 (-3540 3810);
PAINT MONO (-3540 3810);
DISPLAY INVISIBLE (-3540 3810);
FORCEPROP 1 LASTPIN (-3550 3800) BN 4
J 0
(-3562 3808);
DISPLAY 0.489362 (-3562 3808);
PAINT GREEN (-3562 3808);
FORCEPROP 2 LAST CDS_LIB mstr_standard
J 0
(-3500 3800);
DISPLAY 0.723404 (-3500 3800);
PAINT MONO (-3500 3800);
DISPLAY INVISIBLE (-3500 3800);
FORCEPROP 1 LAST BODY_TYPE PLUMBING
J 0
(-3500 3850);
DISPLAY 0.872340 (-3500 3850);
PAINT GREEN (-3500 3850);
DISPLAY INVISIBLE (-3500 3850);
FORCEPROP 1 LAST HDL_TAP TRUE
J 0
(-3175 3675);
DISPLAY 0.872340 (-3175 3675);
DISPLAY INVISIBLE (-3175 3675);
FORCEPROP 1 LAST PATH I206
J 0
(-3502 3800);
DISPLAY 0.872340 (-3502 3800);
PAINT GREEN (-3502 3800);
DISPLAY INVISIBLE (-3502 3800);
FORCEADD TAP..1
(-3300 3550);
FORCEPROP 3 LASTPIN (-3350 3550) SIG_NAME M_L_CPU0_SA_DQS_DN<2>
J 0
(-3340 3560);
DISPLAY 0.659574 (-3340 3560);
PAINT MONO (-3340 3560);
DISPLAY INVISIBLE (-3340 3560);
FORCEPROP 1 LASTPIN (-3350 3550) BN 2
J 0
(-3362 3558);
DISPLAY 0.489362 (-3362 3558);
PAINT GREEN (-3362 3558);
FORCEPROP 2 LAST CDS_LIB mstr_standard
J 0
(-3300 3550);
DISPLAY 0.723404 (-3300 3550);
PAINT MONO (-3300 3550);
DISPLAY INVISIBLE (-3300 3550);
FORCEPROP 1 LAST BODY_TYPE PLUMBING
J 0
(-3300 3600);
DISPLAY 0.872340 (-3300 3600);
PAINT GREEN (-3300 3600);
DISPLAY INVISIBLE (-3300 3600);
FORCEPROP 1 LAST HDL_TAP TRUE
J 0
(-2975 3425);
DISPLAY 0.872340 (-2975 3425);
DISPLAY INVISIBLE (-2975 3425);
FORCEPROP 1 LAST PATH I207
J 0
(-3302 3550);
DISPLAY 0.872340 (-3302 3550);
PAINT GREEN (-3302 3550);
DISPLAY INVISIBLE (-3302 3550);
FORCEADD TAP..1
(-3300 3650);
FORCEPROP 3 LASTPIN (-3350 3650) SIG_NAME M_L_CPU0_SA_DQS_DN<3>
J 0
(-3340 3660);
DISPLAY 0.659574 (-3340 3660);
PAINT MONO (-3340 3660);
DISPLAY INVISIBLE (-3340 3660);
FORCEPROP 1 LASTPIN (-3350 3650) BN 3
J 0
(-3362 3658);
DISPLAY 0.489362 (-3362 3658);
PAINT GREEN (-3362 3658);
FORCEPROP 2 LAST CDS_LIB mstr_standard
J 0
(-3300 3650);
DISPLAY 0.723404 (-3300 3650);
PAINT MONO (-3300 3650);
DISPLAY INVISIBLE (-3300 3650);
FORCEPROP 1 LAST BODY_TYPE PLUMBING
J 0
(-3300 3700);
DISPLAY 0.872340 (-3300 3700);
PAINT GREEN (-3300 3700);
DISPLAY INVISIBLE (-3300 3700);
FORCEPROP 1 LAST HDL_TAP TRUE
J 0
(-2975 3525);
DISPLAY 0.872340 (-2975 3525);
DISPLAY INVISIBLE (-2975 3525);
FORCEPROP 1 LAST PATH I208
J 0
(-3302 3650);
DISPLAY 0.872340 (-3302 3650);
PAINT GREEN (-3302 3650);
DISPLAY INVISIBLE (-3302 3650);
FORCEADD TAP..1
(-3300 3450);
FORCEPROP 3 LASTPIN (-3350 3450) SIG_NAME M_L_CPU0_SA_DQS_DN<1>
J 0
(-3340 3460);
DISPLAY 0.659574 (-3340 3460);
PAINT MONO (-3340 3460);
DISPLAY INVISIBLE (-3340 3460);
FORCEPROP 1 LASTPIN (-3350 3450) BN 1
J 0
(-3362 3458);
DISPLAY 0.489362 (-3362 3458);
PAINT GREEN (-3362 3458);
FORCEPROP 2 LAST CDS_LIB mstr_standard
J 0
(-3300 3450);
DISPLAY 0.723404 (-3300 3450);
PAINT MONO (-3300 3450);
DISPLAY INVISIBLE (-3300 3450);
FORCEPROP 1 LAST BODY_TYPE PLUMBING
J 0
(-3300 3500);
DISPLAY 0.872340 (-3300 3500);
PAINT GREEN (-3300 3500);
DISPLAY INVISIBLE (-3300 3500);
FORCEPROP 1 LAST HDL_TAP TRUE
J 0
(-2975 3325);
DISPLAY 0.872340 (-2975 3325);
DISPLAY INVISIBLE (-2975 3325);
FORCEPROP 1 LAST PATH I209
J 0
(-3302 3450);
DISPLAY 0.872340 (-3302 3450);
PAINT GREEN (-3302 3450);
DISPLAY INVISIBLE (-3302 3450);
FORCEADD OFFPAGE..1
(-8325 4725);
FORCEPROP 2 LAST $XR0 21 
J 0
(-8546 4725);
DISPLAY 0.638298 (-8546 4725);
PAINT MONO (-8546 4725);
FORCEPROP 2 LAST CDS_LIB mstr_standard
J 0
(-8325 4725);
DISPLAY 0.723404 (-8325 4725);
PAINT MONO (-8325 4725);
DISPLAY INVISIBLE (-8325 4725);
FORCEPROP 1 LAST OFFPAGE TRUE
J 0
(-8000 4600);
DISPLAY 0.872340 (-8000 4600);
PAINT GREEN (-8000 4600);
DISPLAY INVISIBLE (-8000 4600);
FORCEPROP 1 LAST COMMENT_BODY TRUE
J 0
(-8200 4625);
DISPLAY 0.872340 (-8200 4625);
PAINT GREEN (-8200 4625);
DISPLAY INVISIBLE (-8200 4625);
FORCEPROP 2 LAST PATH I21
J 0
(-8275 4800);
DISPLAY 1.021277 (-8275 4800);
DISPLAY INVISIBLE (-8275 4800);
FORCEADD TAP..1
(-3500 3600);
FORCEPROP 3 LASTPIN (-3550 3600) SIG_NAME M_L_CPU0_SA_DQS_DP<2>
J 0
(-3540 3610);
DISPLAY 0.659574 (-3540 3610);
PAINT MONO (-3540 3610);
DISPLAY INVISIBLE (-3540 3610);
FORCEPROP 1 LASTPIN (-3550 3600) BN 2
J 0
(-3562 3608);
DISPLAY 0.489362 (-3562 3608);
PAINT GREEN (-3562 3608);
FORCEPROP 2 LAST CDS_LIB mstr_standard
J 0
(-3500 3600);
DISPLAY 0.723404 (-3500 3600);
PAINT MONO (-3500 3600);
DISPLAY INVISIBLE (-3500 3600);
FORCEPROP 1 LAST BODY_TYPE PLUMBING
J 0
(-3500 3650);
DISPLAY 0.872340 (-3500 3650);
PAINT GREEN (-3500 3650);
DISPLAY INVISIBLE (-3500 3650);
FORCEPROP 1 LAST HDL_TAP TRUE
J 0
(-3175 3475);
DISPLAY 0.872340 (-3175 3475);
DISPLAY INVISIBLE (-3175 3475);
FORCEPROP 1 LAST PATH I210
J 0
(-3502 3600);
DISPLAY 0.872340 (-3502 3600);
PAINT GREEN (-3502 3600);
DISPLAY INVISIBLE (-3502 3600);
FORCEADD TAP..1
(-3500 3500);
FORCEPROP 3 LASTPIN (-3550 3500) SIG_NAME M_L_CPU0_SA_DQS_DP<1>
J 0
(-3540 3510);
DISPLAY 0.659574 (-3540 3510);
PAINT MONO (-3540 3510);
DISPLAY INVISIBLE (-3540 3510);
FORCEPROP 1 LASTPIN (-3550 3500) BN 1
J 0
(-3562 3508);
DISPLAY 0.489362 (-3562 3508);
PAINT GREEN (-3562 3508);
FORCEPROP 2 LAST CDS_LIB mstr_standard
J 0
(-3500 3500);
DISPLAY 0.723404 (-3500 3500);
PAINT MONO (-3500 3500);
DISPLAY INVISIBLE (-3500 3500);
FORCEPROP 1 LAST BODY_TYPE PLUMBING
J 0
(-3500 3550);
DISPLAY 0.872340 (-3500 3550);
PAINT GREEN (-3500 3550);
DISPLAY INVISIBLE (-3500 3550);
FORCEPROP 1 LAST HDL_TAP TRUE
J 0
(-3175 3375);
DISPLAY 0.872340 (-3175 3375);
DISPLAY INVISIBLE (-3175 3375);
FORCEPROP 1 LAST PATH I211
J 0
(-3502 3500);
DISPLAY 0.872340 (-3502 3500);
PAINT GREEN (-3502 3500);
DISPLAY INVISIBLE (-3502 3500);
FORCEADD OFFPAGE..2
(-2500 3250);
FORCEPROP 2 LAST $XR0 21 
J 0
(-2311 3250);
DISPLAY 0.638298 (-2311 3250);
PAINT MONO (-2311 3250);
FORCEPROP 2 LAST PATH I212
J 0
(-2300 3300);
DISPLAY 0.680851 (-2300 3300);
DISPLAY INVISIBLE (-2300 3300);
FORCEPROP 2 LAST CDS_LIB mstr_standard
J 0
(-2500 3250);
DISPLAY 0.723404 (-2500 3250);
PAINT MONO (-2500 3250);
DISPLAY INVISIBLE (-2500 3250);
FORCEPROP 1 LAST OFFPAGE TRUE
J 0
(-2175 3125);
DISPLAY 0.723404 (-2175 3125);
PAINT GREEN (-2175 3125);
DISPLAY INVISIBLE (-2175 3125);
FORCEPROP 1 LAST COMMENT_BODY TRUE
J 0
(-2545 3155);
DISPLAY 0.872340 (-2545 3155);
PAINT GREEN (-2545 3155);
DISPLAY INVISIBLE (-2545 3155);
FORCEADD OFFPAGE..2
(-2500 3300);
FORCEPROP 2 LAST $XR0 21 
J 0
(-2311 3300);
DISPLAY 0.638298 (-2311 3300);
PAINT MONO (-2311 3300);
FORCEPROP 2 LAST PATH I213
J 0
(-2300 3350);
DISPLAY 0.680851 (-2300 3350);
DISPLAY INVISIBLE (-2300 3350);
FORCEPROP 2 LAST CDS_LIB mstr_standard
J 0
(-2500 3300);
DISPLAY 0.723404 (-2500 3300);
PAINT MONO (-2500 3300);
DISPLAY INVISIBLE (-2500 3300);
FORCEPROP 1 LAST OFFPAGE TRUE
J 0
(-2175 3175);
DISPLAY 0.723404 (-2175 3175);
PAINT GREEN (-2175 3175);
DISPLAY INVISIBLE (-2175 3175);
FORCEPROP 1 LAST COMMENT_BODY TRUE
J 0
(-2545 3205);
DISPLAY 0.872340 (-2545 3205);
PAINT GREEN (-2545 3205);
DISPLAY INVISIBLE (-2545 3205);
FORCEADD TAP..1
(-3300 3200);
FORCEPROP 3 LASTPIN (-3350 3200) SIG_NAME M_L_CPU0_SB_DQS_DN<9>
J 0
(-3340 3210);
DISPLAY 0.659574 (-3340 3210);
PAINT MONO (-3340 3210);
DISPLAY INVISIBLE (-3340 3210);
FORCEPROP 1 LASTPIN (-3350 3200) BN 9
J 0
(-3362 3208);
DISPLAY 0.489362 (-3362 3208);
PAINT GREEN (-3362 3208);
FORCEPROP 2 LAST CDS_LIB mstr_standard
J 0
(-3300 3200);
DISPLAY 0.723404 (-3300 3200);
PAINT MONO (-3300 3200);
DISPLAY INVISIBLE (-3300 3200);
FORCEPROP 1 LAST BODY_TYPE PLUMBING
J 0
(-3300 3250);
DISPLAY 0.872340 (-3300 3250);
PAINT GREEN (-3300 3250);
DISPLAY INVISIBLE (-3300 3250);
FORCEPROP 1 LAST HDL_TAP TRUE
J 0
(-2975 3075);
DISPLAY 0.872340 (-2975 3075);
DISPLAY INVISIBLE (-2975 3075);
FORCEPROP 1 LAST PATH I214
J 0
(-3302 3200);
DISPLAY 0.872340 (-3302 3200);
PAINT GREEN (-3302 3200);
DISPLAY INVISIBLE (-3302 3200);
FORCEADD TAP..1
(-3300 3350);
FORCEPROP 3 LASTPIN (-3350 3350) SIG_NAME M_L_CPU0_SA_DQS_DN<0>
J 0
(-3340 3360);
DISPLAY 0.659574 (-3340 3360);
PAINT MONO (-3340 3360);
DISPLAY INVISIBLE (-3340 3360);
FORCEPROP 1 LASTPIN (-3350 3350) BN 0
J 0
(-3362 3358);
DISPLAY 0.489362 (-3362 3358);
PAINT GREEN (-3362 3358);
FORCEPROP 2 LAST CDS_LIB mstr_standard
J 0
(-3300 3350);
DISPLAY 0.723404 (-3300 3350);
PAINT MONO (-3300 3350);
DISPLAY INVISIBLE (-3300 3350);
FORCEPROP 1 LAST BODY_TYPE PLUMBING
J 0
(-3300 3400);
DISPLAY 0.872340 (-3300 3400);
PAINT GREEN (-3300 3400);
DISPLAY INVISIBLE (-3300 3400);
FORCEPROP 1 LAST HDL_TAP TRUE
J 0
(-2975 3225);
DISPLAY 0.872340 (-2975 3225);
DISPLAY INVISIBLE (-2975 3225);
FORCEPROP 1 LAST PATH I215
J 0
(-3302 3350);
DISPLAY 0.872340 (-3302 3350);
PAINT GREEN (-3302 3350);
DISPLAY INVISIBLE (-3302 3350);
FORCEADD TAP..1
(-3500 3400);
FORCEPROP 3 LASTPIN (-3550 3400) SIG_NAME M_L_CPU0_SA_DQS_DP<0>
J 0
(-3540 3410);
DISPLAY 0.659574 (-3540 3410);
PAINT MONO (-3540 3410);
DISPLAY INVISIBLE (-3540 3410);
FORCEPROP 1 LASTPIN (-3550 3400) BN 0
J 0
(-3562 3408);
DISPLAY 0.489362 (-3562 3408);
PAINT GREEN (-3562 3408);
FORCEPROP 2 LAST CDS_LIB mstr_standard
J 0
(-3500 3400);
DISPLAY 0.723404 (-3500 3400);
PAINT MONO (-3500 3400);
DISPLAY INVISIBLE (-3500 3400);
FORCEPROP 1 LAST BODY_TYPE PLUMBING
J 0
(-3500 3450);
DISPLAY 0.872340 (-3500 3450);
PAINT GREEN (-3500 3450);
DISPLAY INVISIBLE (-3500 3450);
FORCEPROP 1 LAST HDL_TAP TRUE
J 0
(-3175 3275);
DISPLAY 0.872340 (-3175 3275);
DISPLAY INVISIBLE (-3175 3275);
FORCEPROP 1 LAST PATH I216
J 0
(-3502 3400);
DISPLAY 0.872340 (-3502 3400);
PAINT GREEN (-3502 3400);
DISPLAY INVISIBLE (-3502 3400);
FORCEADD TAP..1
(-3500 3250);
FORCEPROP 3 LASTPIN (-3550 3250) SIG_NAME M_L_CPU0_SB_DQS_DP<9>
J 0
(-3540 3260);
DISPLAY 0.659574 (-3540 3260);
PAINT MONO (-3540 3260);
DISPLAY INVISIBLE (-3540 3260);
FORCEPROP 1 LASTPIN (-3550 3250) BN 9
J 0
(-3562 3258);
DISPLAY 0.489362 (-3562 3258);
PAINT GREEN (-3562 3258);
FORCEPROP 2 LAST CDS_LIB mstr_standard
J 0
(-3500 3250);
DISPLAY 0.723404 (-3500 3250);
PAINT MONO (-3500 3250);
DISPLAY INVISIBLE (-3500 3250);
FORCEPROP 1 LAST BODY_TYPE PLUMBING
J 0
(-3500 3300);
DISPLAY 0.872340 (-3500 3300);
PAINT GREEN (-3500 3300);
DISPLAY INVISIBLE (-3500 3300);
FORCEPROP 1 LAST HDL_TAP TRUE
J 0
(-3175 3125);
DISPLAY 0.872340 (-3175 3125);
DISPLAY INVISIBLE (-3175 3125);
FORCEPROP 1 LAST PATH I217
J 0
(-3502 3250);
DISPLAY 0.872340 (-3502 3250);
PAINT GREEN (-3502 3250);
DISPLAY INVISIBLE (-3502 3250);
FORCEADD TAP..1
(-3300 3100);
FORCEPROP 3 LASTPIN (-3350 3100) SIG_NAME M_L_CPU0_SB_DQS_DN<8>
J 0
(-3340 3110);
DISPLAY 0.659574 (-3340 3110);
PAINT MONO (-3340 3110);
DISPLAY INVISIBLE (-3340 3110);
FORCEPROP 1 LASTPIN (-3350 3100) BN 8
J 0
(-3362 3108);
DISPLAY 0.489362 (-3362 3108);
PAINT GREEN (-3362 3108);
FORCEPROP 2 LAST CDS_LIB mstr_standard
J 0
(-3300 3100);
DISPLAY 0.723404 (-3300 3100);
PAINT MONO (-3300 3100);
DISPLAY INVISIBLE (-3300 3100);
FORCEPROP 1 LAST BODY_TYPE PLUMBING
J 0
(-3300 3150);
DISPLAY 0.872340 (-3300 3150);
PAINT GREEN (-3300 3150);
DISPLAY INVISIBLE (-3300 3150);
FORCEPROP 1 LAST HDL_TAP TRUE
J 0
(-2975 2975);
DISPLAY 0.872340 (-2975 2975);
DISPLAY INVISIBLE (-2975 2975);
FORCEPROP 1 LAST PATH I218
J 0
(-3302 3100);
DISPLAY 0.872340 (-3302 3100);
PAINT GREEN (-3302 3100);
DISPLAY INVISIBLE (-3302 3100);
FORCEADD TAP..1
(-3300 3000);
FORCEPROP 3 LASTPIN (-3350 3000) SIG_NAME M_L_CPU0_SB_DQS_DN<7>
J 0
(-3340 3010);
DISPLAY 0.659574 (-3340 3010);
PAINT MONO (-3340 3010);
DISPLAY INVISIBLE (-3340 3010);
FORCEPROP 1 LASTPIN (-3350 3000) BN 7
J 0
(-3362 3008);
DISPLAY 0.489362 (-3362 3008);
PAINT GREEN (-3362 3008);
FORCEPROP 2 LAST CDS_LIB mstr_standard
J 0
(-3300 3000);
DISPLAY 0.723404 (-3300 3000);
PAINT MONO (-3300 3000);
DISPLAY INVISIBLE (-3300 3000);
FORCEPROP 1 LAST BODY_TYPE PLUMBING
J 0
(-3300 3050);
DISPLAY 0.872340 (-3300 3050);
PAINT GREEN (-3300 3050);
DISPLAY INVISIBLE (-3300 3050);
FORCEPROP 1 LAST HDL_TAP TRUE
J 0
(-2975 2875);
DISPLAY 0.872340 (-2975 2875);
DISPLAY INVISIBLE (-2975 2875);
FORCEPROP 1 LAST PATH I219
J 0
(-3302 3000);
DISPLAY 0.872340 (-3302 3000);
PAINT GREEN (-3302 3000);
DISPLAY INVISIBLE (-3302 3000);
FORCEADD SCONN288_DDR506112002KQ..1
(-6875 3325);
FORCEPROP 1 LAST LOCATION J67
J 0
(-7325 5400);
DISPLAY 0.468085 (-7325 5400);
PAINT SKYBLUE (-7325 5400);
FORCEPROP 0 LAST $SEC 1
J 0
(-7325 5550);
DISPLAY 0.680851 (-7325 5550);
PAINT MONO (-7325 5550);
DISPLAY INVISIBLE (-7325 5550);
FORCEPROP 2 LAST CDS_SEC 1
J 0
(-7325 5550);
DISPLAY 1.021277 (-7325 5550);
DISPLAY INVISIBLE (-7325 5550);
FORCEPROP 0 LASTPIN (-7475 2725) $PN 62
J 2
(-7485 2735);
DISPLAY 0.680851 (-7485 2735);
PAINT MONO (-7485 2735);
FORCEPROP 0 LASTPIN (-7475 4775) $PN 66
J 2
(-7485 4785);
DISPLAY 0.680851 (-7485 4785);
PAINT MONO (-7485 4785);
FORCEPROP 0 LASTPIN (-7475 4375) $PN 76
J 2
(-7485 4385);
DISPLAY 0.680851 (-7485 4385);
PAINT MONO (-7485 4385);
FORCEPROP 0 LASTPIN (-7475 4825) $PN 211
J 2
(-7485 4835);
DISPLAY 0.680851 (-7485 4835);
PAINT MONO (-7485 4835);
FORCEPROP 0 LASTPIN (-7475 4425) $PN 221
J 2
(-7485 4435);
DISPLAY 0.680851 (-7485 4435);
PAINT MONO (-7485 4435);
FORCEPROP 0 LASTPIN (-7475 4875) $PN 68
J 2
(-7485 4885);
DISPLAY 0.680851 (-7485 4885);
PAINT MONO (-7485 4885);
FORCEPROP 0 LASTPIN (-7475 4475) $PN 78
J 2
(-7485 4485);
DISPLAY 0.680851 (-7485 4485);
PAINT MONO (-7485 4485);
FORCEPROP 0 LASTPIN (-7475 4925) $PN 213
J 2
(-7485 4935);
DISPLAY 0.680851 (-7485 4935);
PAINT MONO (-7485 4935);
FORCEPROP 0 LASTPIN (-7475 4525) $PN 223
J 2
(-7485 4535);
DISPLAY 0.680851 (-7485 4535);
PAINT MONO (-7485 4535);
FORCEPROP 0 LASTPIN (-7475 4975) $PN 70
J 2
(-7485 4985);
DISPLAY 0.680851 (-7485 4985);
PAINT MONO (-7485 4985);
FORCEPROP 0 LASTPIN (-7475 4575) $PN 80
J 2
(-7485 4585);
DISPLAY 0.680851 (-7485 4585);
PAINT MONO (-7485 4585);
FORCEPROP 0 LASTPIN (-7475 5025) $PN 215
J 2
(-7485 5035);
DISPLAY 0.680851 (-7485 5035);
PAINT MONO (-7485 5035);
FORCEPROP 0 LASTPIN (-7475 4625) $PN 225
J 2
(-7485 4635);
DISPLAY 0.680851 (-7485 4635);
PAINT MONO (-7485 4635);
FORCEPROP 0 LASTPIN (-7475 5075) $PN 72
J 2
(-7485 5085);
DISPLAY 0.680851 (-7485 5085);
PAINT MONO (-7485 5085);
FORCEPROP 0 LASTPIN (-7475 4675) $PN 82
J 2
(-7485 4685);
DISPLAY 0.680851 (-7485 4685);
PAINT MONO (-7485 4685);
FORCEPROP 0 LASTPIN (-7475 3325) $PN 51
J 2
(-7485 3335);
DISPLAY 0.680851 (-7485 3335);
PAINT MONO (-7485 3335);
FORCEPROP 0 LASTPIN (-7475 2875) $PN 96
J 2
(-7485 2885);
DISPLAY 0.680851 (-7485 2885);
PAINT MONO (-7485 2885);
FORCEPROP 0 LASTPIN (-7475 3375) $PN 53
J 2
(-7485 3385);
DISPLAY 0.680851 (-7485 3385);
PAINT MONO (-7485 3385);
FORCEPROP 0 LASTPIN (-7475 2925) $PN 98
J 2
(-7485 2935);
DISPLAY 0.680851 (-7485 2935);
PAINT MONO (-7485 2935);
FORCEPROP 0 LASTPIN (-7475 3425) $PN 196
J 2
(-7485 3435);
DISPLAY 0.680851 (-7485 3435);
PAINT MONO (-7485 3435);
FORCEPROP 0 LASTPIN (-7475 2975) $PN 241
J 2
(-7485 2985);
DISPLAY 0.680851 (-7485 2985);
PAINT MONO (-7485 2985);
FORCEPROP 0 LASTPIN (-7475 3475) $PN 198
J 2
(-7485 3485);
DISPLAY 0.680851 (-7485 3485);
PAINT MONO (-7485 3485);
FORCEPROP 0 LASTPIN (-7475 3025) $PN 243
J 2
(-7485 3035);
DISPLAY 0.680851 (-7485 3035);
PAINT MONO (-7485 3035);
FORCEPROP 0 LASTPIN (-7475 3525) $PN 58
J 2
(-7485 3535);
DISPLAY 0.680851 (-7485 3535);
PAINT MONO (-7485 3535);
FORCEPROP 0 LASTPIN (-7475 3075) $PN 89
J 2
(-7485 3085);
DISPLAY 0.680851 (-7485 3085);
PAINT MONO (-7485 3085);
FORCEPROP 0 LASTPIN (-7475 3575) $PN 60
J 2
(-7485 3585);
DISPLAY 0.680851 (-7485 3585);
PAINT MONO (-7485 3585);
FORCEPROP 0 LASTPIN (-7475 3125) $PN 91
J 2
(-7485 3135);
DISPLAY 0.680851 (-7485 3135);
PAINT MONO (-7485 3135);
FORCEPROP 0 LASTPIN (-7475 3625) $PN 203
J 2
(-7485 3635);
DISPLAY 0.680851 (-7485 3635);
PAINT MONO (-7485 3635);
FORCEPROP 0 LASTPIN (-7475 3175) $PN 234
J 2
(-7485 3185);
DISPLAY 0.680851 (-7485 3185);
PAINT MONO (-7485 3185);
FORCEPROP 0 LASTPIN (-7475 3675) $PN 205
J 2
(-7485 3685);
DISPLAY 0.680851 (-7485 3685);
PAINT MONO (-7485 3685);
FORCEPROP 0 LASTPIN (-7475 3225) $PN 236
J 2
(-7485 3235);
DISPLAY 0.680851 (-7485 3235);
PAINT MONO (-7485 3235);
FORCEPROP 0 LASTPIN (-7475 3775) $PN 218
J 2
(-7485 3785);
DISPLAY 0.680851 (-7485 3785);
PAINT MONO (-7485 3785);
FORCEPROP 0 LASTPIN (-7475 3825) $PN 217
J 2
(-7485 3835);
DISPLAY 0.680851 (-7485 3835);
PAINT MONO (-7485 3835);
FORCEPROP 0 LASTPIN (-7475 4075) $PN 64
J 2
(-7485 4085);
DISPLAY 0.680851 (-7485 4085);
PAINT MONO (-7485 4085);
FORCEPROP 0 LASTPIN (-7475 3925) $PN 84
J 2
(-7485 3935);
DISPLAY 0.680851 (-7485 3935);
PAINT MONO (-7485 3935);
FORCEPROP 0 LASTPIN (-7475 4125) $PN 209
J 2
(-7485 4135);
DISPLAY 0.680851 (-7485 4135);
PAINT MONO (-7485 4135);
FORCEPROP 0 LASTPIN (-7475 3975) $PN 229
J 2
(-7485 3985);
DISPLAY 0.680851 (-7485 3985);
PAINT MONO (-7485 3985);
FORCEPROP 0 LASTPIN (-6275 3525) $PN 7
J 0
(-6265 3535);
DISPLAY 0.680851 (-6265 3535);
PAINT MONO (-6265 3535);
FORCEPROP 0 LASTPIN (-6275 1875) $PN 100
J 0
(-6265 1885);
DISPLAY 0.680851 (-6265 1885);
PAINT MONO (-6265 1885);
FORCEPROP 0 LASTPIN (-6275 3575) $PN 9
J 0
(-6265 3585);
DISPLAY 0.680851 (-6265 3585);
PAINT MONO (-6265 3585);
FORCEPROP 0 LASTPIN (-6275 1925) $PN 102
J 0
(-6265 1935);
DISPLAY 0.680851 (-6265 1935);
PAINT MONO (-6265 1935);
FORCEPROP 0 LASTPIN (-6275 3625) $PN 152
J 0
(-6265 3635);
DISPLAY 0.680851 (-6265 3635);
PAINT MONO (-6265 3635);
FORCEPROP 0 LASTPIN (-6275 1975) $PN 245
J 0
(-6265 1985);
DISPLAY 0.680851 (-6265 1985);
PAINT MONO (-6265 1985);
FORCEPROP 0 LASTPIN (-6275 3675) $PN 154
J 0
(-6265 3685);
DISPLAY 0.680851 (-6265 3685);
PAINT MONO (-6265 3685);
FORCEPROP 0 LASTPIN (-6275 2025) $PN 247
J 0
(-6265 2035);
DISPLAY 0.680851 (-6265 2035);
PAINT MONO (-6265 2035);
FORCEPROP 0 LASTPIN (-6275 3725) $PN 14
J 0
(-6265 3735);
DISPLAY 0.680851 (-6265 3735);
PAINT MONO (-6265 3735);
FORCEPROP 0 LASTPIN (-6275 2075) $PN 107
J 0
(-6265 2085);
DISPLAY 0.680851 (-6265 2085);
PAINT MONO (-6265 2085);
FORCEPROP 0 LASTPIN (-6275 3775) $PN 16
J 0
(-6265 3785);
DISPLAY 0.680851 (-6265 3785);
PAINT MONO (-6265 3785);
FORCEPROP 0 LASTPIN (-6275 2125) $PN 109
J 0
(-6265 2135);
DISPLAY 0.680851 (-6265 2135);
PAINT MONO (-6265 2135);
FORCEPROP 0 LASTPIN (-6275 3825) $PN 159
J 0
(-6265 3835);
DISPLAY 0.680851 (-6265 3835);
PAINT MONO (-6265 3835);
FORCEPROP 0 LASTPIN (-6275 2175) $PN 252
J 0
(-6265 2185);
DISPLAY 0.680851 (-6265 2185);
PAINT MONO (-6265 2185);
FORCEPROP 0 LASTPIN (-6275 3875) $PN 161
J 0
(-6265 3885);
DISPLAY 0.680851 (-6265 3885);
PAINT MONO (-6265 3885);
FORCEPROP 0 LASTPIN (-6275 2225) $PN 254
J 0
(-6265 2235);
DISPLAY 0.680851 (-6265 2235);
PAINT MONO (-6265 2235);
FORCEPROP 0 LASTPIN (-6275 3925) $PN 18
J 0
(-6265 3935);
DISPLAY 0.680851 (-6265 3935);
PAINT MONO (-6265 3935);
FORCEPROP 0 LASTPIN (-6275 2275) $PN 111
J 0
(-6265 2285);
DISPLAY 0.680851 (-6265 2285);
PAINT MONO (-6265 2285);
FORCEPROP 0 LASTPIN (-6275 3975) $PN 20
J 0
(-6265 3985);
DISPLAY 0.680851 (-6265 3985);
PAINT MONO (-6265 3985);
FORCEPROP 0 LASTPIN (-6275 2325) $PN 113
J 0
(-6265 2335);
DISPLAY 0.680851 (-6265 2335);
PAINT MONO (-6265 2335);
FORCEPROP 0 LASTPIN (-6275 4025) $PN 163
J 0
(-6265 4035);
DISPLAY 0.680851 (-6265 4035);
PAINT MONO (-6265 4035);
FORCEPROP 0 LASTPIN (-6275 2375) $PN 256
J 0
(-6265 2385);
DISPLAY 0.680851 (-6265 2385);
PAINT MONO (-6265 2385);
FORCEPROP 0 LASTPIN (-6275 4075) $PN 165
J 0
(-6265 4085);
DISPLAY 0.680851 (-6265 4085);
PAINT MONO (-6265 4085);
FORCEPROP 0 LASTPIN (-6275 2425) $PN 258
J 0
(-6265 2435);
DISPLAY 0.680851 (-6265 2435);
PAINT MONO (-6265 2435);
FORCEPROP 0 LASTPIN (-6275 4125) $PN 25
J 0
(-6265 4135);
DISPLAY 0.680851 (-6265 4135);
PAINT MONO (-6265 4135);
FORCEPROP 0 LASTPIN (-6275 2475) $PN 118
J 0
(-6265 2485);
DISPLAY 0.680851 (-6265 2485);
PAINT MONO (-6265 2485);
FORCEPROP 0 LASTPIN (-6275 4175) $PN 27
J 0
(-6265 4185);
DISPLAY 0.680851 (-6265 4185);
PAINT MONO (-6265 4185);
FORCEPROP 0 LASTPIN (-6275 2525) $PN 120
J 0
(-6265 2535);
DISPLAY 0.680851 (-6265 2535);
PAINT MONO (-6265 2535);
FORCEPROP 0 LASTPIN (-6275 4225) $PN 170
J 0
(-6265 4235);
DISPLAY 0.680851 (-6265 4235);
PAINT MONO (-6265 4235);
FORCEPROP 0 LASTPIN (-6275 2575) $PN 263
J 0
(-6265 2585);
DISPLAY 0.680851 (-6265 2585);
PAINT MONO (-6265 2585);
FORCEPROP 0 LASTPIN (-6275 4275) $PN 172
J 0
(-6265 4285);
DISPLAY 0.680851 (-6265 4285);
PAINT MONO (-6265 4285);
FORCEPROP 0 LASTPIN (-6275 2625) $PN 265
J 0
(-6265 2635);
DISPLAY 0.680851 (-6265 2635);
PAINT MONO (-6265 2635);
FORCEPROP 0 LASTPIN (-6275 4325) $PN 29
J 0
(-6265 4335);
DISPLAY 0.680851 (-6265 4335);
PAINT MONO (-6265 4335);
FORCEPROP 0 LASTPIN (-6275 2675) $PN 122
J 0
(-6265 2685);
DISPLAY 0.680851 (-6265 2685);
PAINT MONO (-6265 2685);
FORCEPROP 0 LASTPIN (-6275 4375) $PN 31
J 0
(-6265 4385);
DISPLAY 0.680851 (-6265 4385);
PAINT MONO (-6265 4385);
FORCEPROP 0 LASTPIN (-6275 2725) $PN 124
J 0
(-6265 2735);
DISPLAY 0.680851 (-6265 2735);
PAINT MONO (-6265 2735);
FORCEPROP 0 LASTPIN (-6275 4425) $PN 174
J 0
(-6265 4435);
DISPLAY 0.680851 (-6265 4435);
PAINT MONO (-6265 4435);
FORCEPROP 0 LASTPIN (-6275 2775) $PN 267
J 0
(-6265 2785);
DISPLAY 0.680851 (-6265 2785);
PAINT MONO (-6265 2785);
FORCEPROP 0 LASTPIN (-6275 4475) $PN 176
J 0
(-6265 4485);
DISPLAY 0.680851 (-6265 4485);
PAINT MONO (-6265 4485);
FORCEPROP 0 LASTPIN (-6275 2825) $PN 269
J 0
(-6265 2835);
DISPLAY 0.680851 (-6265 2835);
PAINT MONO (-6265 2835);
FORCEPROP 0 LASTPIN (-6275 4525) $PN 36
J 0
(-6265 4535);
DISPLAY 0.680851 (-6265 4535);
PAINT MONO (-6265 4535);
FORCEPROP 0 LASTPIN (-6275 2875) $PN 129
J 0
(-6265 2885);
DISPLAY 0.680851 (-6265 2885);
PAINT MONO (-6265 2885);
FORCEPROP 0 LASTPIN (-6275 4575) $PN 38
J 0
(-6265 4585);
DISPLAY 0.680851 (-6265 4585);
PAINT MONO (-6265 4585);
FORCEPROP 0 LASTPIN (-6275 2925) $PN 131
J 0
(-6265 2935);
DISPLAY 0.680851 (-6265 2935);
PAINT MONO (-6265 2935);
FORCEPROP 0 LASTPIN (-6275 4625) $PN 181
J 0
(-6265 4635);
DISPLAY 0.680851 (-6265 4635);
PAINT MONO (-6265 4635);
FORCEPROP 0 LASTPIN (-6275 2975) $PN 274
J 0
(-6265 2985);
DISPLAY 0.680851 (-6265 2985);
PAINT MONO (-6265 2985);
FORCEPROP 0 LASTPIN (-6275 4675) $PN 183
J 0
(-6265 4685);
DISPLAY 0.680851 (-6265 4685);
PAINT MONO (-6265 4685);
FORCEPROP 0 LASTPIN (-6275 3025) $PN 276
J 0
(-6265 3035);
DISPLAY 0.680851 (-6265 3035);
PAINT MONO (-6265 3035);
FORCEPROP 0 LASTPIN (-6275 4725) $PN 40
J 0
(-6265 4735);
DISPLAY 0.680851 (-6265 4735);
PAINT MONO (-6265 4735);
FORCEPROP 0 LASTPIN (-6275 3075) $PN 133
J 0
(-6265 3085);
DISPLAY 0.680851 (-6265 3085);
PAINT MONO (-6265 3085);
FORCEPROP 0 LASTPIN (-6275 4775) $PN 42
J 0
(-6265 4785);
DISPLAY 0.680851 (-6265 4785);
PAINT MONO (-6265 4785);
FORCEPROP 0 LASTPIN (-6275 3125) $PN 135
J 0
(-6265 3135);
DISPLAY 0.680851 (-6265 3135);
PAINT MONO (-6265 3135);
FORCEPROP 0 LASTPIN (-6275 4825) $PN 185
J 0
(-6265 4835);
DISPLAY 0.680851 (-6265 4835);
PAINT MONO (-6265 4835);
FORCEPROP 0 LASTPIN (-6275 3175) $PN 278
J 0
(-6265 3185);
DISPLAY 0.680851 (-6265 3185);
PAINT MONO (-6265 3185);
FORCEPROP 0 LASTPIN (-6275 4875) $PN 187
J 0
(-6265 4885);
DISPLAY 0.680851 (-6265 4885);
PAINT MONO (-6265 4885);
FORCEPROP 0 LASTPIN (-6275 3225) $PN 280
J 0
(-6265 3235);
DISPLAY 0.680851 (-6265 3235);
PAINT MONO (-6265 3235);
FORCEPROP 0 LASTPIN (-6275 4925) $PN 47
J 0
(-6265 4935);
DISPLAY 0.680851 (-6265 4935);
PAINT MONO (-6265 4935);
FORCEPROP 0 LASTPIN (-6275 3275) $PN 140
J 0
(-6265 3285);
DISPLAY 0.680851 (-6265 3285);
PAINT MONO (-6265 3285);
FORCEPROP 0 LASTPIN (-6275 4975) $PN 49
J 0
(-6265 4985);
DISPLAY 0.680851 (-6265 4985);
PAINT MONO (-6265 4985);
FORCEPROP 0 LASTPIN (-6275 3325) $PN 142
J 0
(-6265 3335);
DISPLAY 0.680851 (-6265 3335);
PAINT MONO (-6265 3335);
FORCEPROP 0 LASTPIN (-6275 5025) $PN 192
J 0
(-6265 5035);
DISPLAY 0.680851 (-6265 5035);
PAINT MONO (-6265 5035);
FORCEPROP 0 LASTPIN (-6275 3375) $PN 285
J 0
(-6265 3385);
DISPLAY 0.680851 (-6265 3385);
PAINT MONO (-6265 3385);
FORCEPROP 0 LASTPIN (-6275 5075) $PN 194
J 0
(-6265 5085);
DISPLAY 0.680851 (-6265 5085);
PAINT MONO (-6265 5085);
FORCEPROP 0 LASTPIN (-6275 3425) $PN 287
J 0
(-6265 3435);
DISPLAY 0.680851 (-6265 3435);
PAINT MONO (-6265 3435);
FORCEPROP 0 LASTPIN (-7475 2575) $PN 148
J 2
(-7485 2585);
DISPLAY 0.680851 (-7485 2585);
PAINT MONO (-7485 2585);
FORCEPROP 0 LASTPIN (-7475 2475) $PN 4
J 2
(-7485 2485);
DISPLAY 0.680851 (-7485 2485);
PAINT MONO (-7485 2485);
FORCEPROP 0 LASTPIN (-7475 2525) $PN 5
J 2
(-7485 2535);
DISPLAY 0.680851 (-7485 2535);
PAINT MONO (-7485 2535);
FORCEPROP 0 LASTPIN (-7475 1675) $PN 86
J 2
(-7485 1685);
DISPLAY 0.680851 (-7485 1685);
PAINT MONO (-7485 1685);
FORCEPROP 0 LASTPIN (-7475 1625) $PN 87
J 2
(-7485 1635);
DISPLAY 0.680851 (-7485 1635);
PAINT MONO (-7485 1635);
FORCEPROP 0 LASTPIN (-7475 4275) $PN 74
J 2
(-7485 4285);
DISPLAY 0.680851 (-7485 4285);
PAINT MONO (-7485 4285);
FORCEPROP 0 LASTPIN (-7475 4225) $PN 227
J 2
(-7485 4235);
DISPLAY 0.680851 (-7485 4235);
PAINT MONO (-7485 4235);
FORCEPROP 0 LASTPIN (-7475 2225) $PN 147
J 2
(-7485 2235);
DISPLAY 0.680851 (-7485 2235);
PAINT MONO (-7485 2235);
FORCEPROP 0 LASTPIN (-7475 2775) $PN 207
J 2
(-7485 2785);
DISPLAY 0.680851 (-7485 2785);
PAINT MONO (-7485 2785);
FORCEPROP 0 LASTPIN (-7475 1825) $PN 2
J 2
(-7485 1835);
DISPLAY 0.680851 (-7485 1835);
PAINT MONO (-7485 1835);
FORCEPROP 0 LASTPIN (-7475 1875) $PN 144
J 2
(-7485 1885);
DISPLAY 0.680851 (-7485 1885);
PAINT MONO (-7485 1885);
FORCEPROP 0 LASTPIN (-7475 1925) $PN 149
J 2
(-7485 1935);
DISPLAY 0.680851 (-7485 1935);
PAINT MONO (-7485 1935);
FORCEPROP 0 LASTPIN (-7475 1975) $PN 150
J 2
(-7485 1985);
DISPLAY 0.680851 (-7485 1985);
PAINT MONO (-7485 1985);
FORCEPROP 0 LASTPIN (-7475 2025) $PN 220
J 2
(-7485 2035);
DISPLAY 0.680851 (-7485 2035);
PAINT MONO (-7485 2035);
FORCEPROP 0 LASTPIN (-7475 2075) $PN 231
J 2
(-7485 2085);
DISPLAY 0.680851 (-7485 2085);
PAINT MONO (-7485 2085);
FORCEPROP 0 LASTPIN (-7475 2125) $PN 232
J 2
(-7485 2135);
DISPLAY 0.680851 (-7485 2135);
PAINT MONO (-7485 2135);
FORCEPROP 0 LASTPIN (-7475 2625) $PN 3
J 2
(-7485 2635);
DISPLAY 0.680851 (-7485 2635);
PAINT MONO (-7485 2635);
FORCEPROP 2 LAST PART_TYPE SMLF
J 0
(-7325 5500);
DISPLAY 1.021277 (-7325 5500);
FORCEPROP 2 LAST VALUE SCONN288_DDR506112002KQ
J 0
(-7325 5450);
DISPLAY 0.489362 (-7325 5450);
PAINT SKYBLUE (-7325 5450);
FORCEPROP 1 LAST MATERIAL IO
J 0
(-7325 5250);
DISPLAY 0.468085 (-7325 5250);
PAINT SKYBLUE (-7325 5250);
FORCEPROP 1 LAST PART_NUMBER DFHST8FS479
J 0
(-7325 5325);
DISPLAY 0.468085 (-7325 5325);
PAINT SKYBLUE (-7325 5325);
FORCEPROP 1 LAST CDS_LMAN_SYM_OUTLINE -450,1900,450,-1850
J 0
(-6875 3325);
DISPLAY 0.468085 (-6875 3325);
PAINT GREEN (-6875 3325);
DISPLAY INVISIBLE (-6875 3325);
FORCEPROP 1 LAST PATH I22
J 0
(-6875 3325);
DISPLAY 0.723404 (-6875 3325);
PAINT GREEN (-6875 3325);
DISPLAY INVISIBLE (-6875 3325);
FORCEPROP 1 LAST NEEDS_NO_SIZE TRUE
J 0
(-6875 3325);
DISPLAY 0.723404 (-6875 3325);
PAINT GREEN (-6875 3325);
DISPLAY INVISIBLE (-6875 3325);
FORCEPROP 2 LAST CDS_LIB pure_quanta
J 0
(-6875 3325);
DISPLAY INVISIBLE (-6875 3325);
FORCEADD TAP..1
(-3500 3150);
FORCEPROP 3 LASTPIN (-3550 3150) SIG_NAME M_L_CPU0_SB_DQS_DP<8>
J 0
(-3540 3160);
DISPLAY 0.659574 (-3540 3160);
PAINT MONO (-3540 3160);
DISPLAY INVISIBLE (-3540 3160);
FORCEPROP 1 LASTPIN (-3550 3150) BN 8
J 0
(-3562 3158);
DISPLAY 0.489362 (-3562 3158);
PAINT GREEN (-3562 3158);
FORCEPROP 2 LAST CDS_LIB mstr_standard
J 0
(-3500 3150);
DISPLAY 0.723404 (-3500 3150);
PAINT MONO (-3500 3150);
DISPLAY INVISIBLE (-3500 3150);
FORCEPROP 1 LAST BODY_TYPE PLUMBING
J 0
(-3500 3200);
DISPLAY 0.872340 (-3500 3200);
PAINT GREEN (-3500 3200);
DISPLAY INVISIBLE (-3500 3200);
FORCEPROP 1 LAST HDL_TAP TRUE
J 0
(-3175 3025);
DISPLAY 0.872340 (-3175 3025);
DISPLAY INVISIBLE (-3175 3025);
FORCEPROP 1 LAST PATH I220
J 0
(-3502 3150);
DISPLAY 0.872340 (-3502 3150);
PAINT GREEN (-3502 3150);
DISPLAY INVISIBLE (-3502 3150);
FORCEADD TAP..1
(-3500 3050);
FORCEPROP 3 LASTPIN (-3550 3050) SIG_NAME M_L_CPU0_SB_DQS_DP<7>
J 0
(-3540 3060);
DISPLAY 0.659574 (-3540 3060);
PAINT MONO (-3540 3060);
DISPLAY INVISIBLE (-3540 3060);
FORCEPROP 1 LASTPIN (-3550 3050) BN 7
J 0
(-3562 3058);
DISPLAY 0.489362 (-3562 3058);
PAINT GREEN (-3562 3058);
FORCEPROP 2 LAST CDS_LIB mstr_standard
J 0
(-3500 3050);
DISPLAY 0.723404 (-3500 3050);
PAINT MONO (-3500 3050);
DISPLAY INVISIBLE (-3500 3050);
FORCEPROP 1 LAST BODY_TYPE PLUMBING
J 0
(-3500 3100);
DISPLAY 0.872340 (-3500 3100);
PAINT GREEN (-3500 3100);
DISPLAY INVISIBLE (-3500 3100);
FORCEPROP 1 LAST HDL_TAP TRUE
J 0
(-3175 2925);
DISPLAY 0.872340 (-3175 2925);
DISPLAY INVISIBLE (-3175 2925);
FORCEPROP 1 LAST PATH I221
J 0
(-3502 3050);
DISPLAY 0.872340 (-3502 3050);
PAINT GREEN (-3502 3050);
DISPLAY INVISIBLE (-3502 3050);
FORCEADD TAP..1
(-3500 2950);
FORCEPROP 3 LASTPIN (-3550 2950) SIG_NAME M_L_CPU0_SB_DQS_DP<6>
J 0
(-3540 2960);
DISPLAY 0.659574 (-3540 2960);
PAINT MONO (-3540 2960);
DISPLAY INVISIBLE (-3540 2960);
FORCEPROP 1 LASTPIN (-3550 2950) BN 6
J 0
(-3562 2958);
DISPLAY 0.489362 (-3562 2958);
PAINT GREEN (-3562 2958);
FORCEPROP 2 LAST CDS_LIB mstr_standard
J 0
(-3500 2950);
DISPLAY 0.723404 (-3500 2950);
PAINT MONO (-3500 2950);
DISPLAY INVISIBLE (-3500 2950);
FORCEPROP 1 LAST BODY_TYPE PLUMBING
J 0
(-3500 3000);
DISPLAY 0.872340 (-3500 3000);
PAINT GREEN (-3500 3000);
DISPLAY INVISIBLE (-3500 3000);
FORCEPROP 1 LAST HDL_TAP TRUE
J 0
(-3175 2825);
DISPLAY 0.872340 (-3175 2825);
DISPLAY INVISIBLE (-3175 2825);
FORCEPROP 1 LAST PATH I222
J 0
(-3502 2950);
DISPLAY 0.872340 (-3502 2950);
PAINT GREEN (-3502 2950);
DISPLAY INVISIBLE (-3502 2950);
FORCEADD TAP..1
(-3300 2800);
FORCEPROP 3 LASTPIN (-3350 2800) SIG_NAME M_L_CPU0_SB_DQS_DN<5>
J 0
(-3340 2810);
DISPLAY 0.659574 (-3340 2810);
PAINT MONO (-3340 2810);
DISPLAY INVISIBLE (-3340 2810);
FORCEPROP 1 LASTPIN (-3350 2800) BN 5
J 0
(-3362 2808);
DISPLAY 0.489362 (-3362 2808);
PAINT GREEN (-3362 2808);
FORCEPROP 2 LAST CDS_LIB mstr_standard
J 0
(-3300 2800);
DISPLAY 0.723404 (-3300 2800);
PAINT MONO (-3300 2800);
DISPLAY INVISIBLE (-3300 2800);
FORCEPROP 1 LAST BODY_TYPE PLUMBING
J 0
(-3300 2850);
DISPLAY 0.872340 (-3300 2850);
PAINT GREEN (-3300 2850);
DISPLAY INVISIBLE (-3300 2850);
FORCEPROP 1 LAST HDL_TAP TRUE
J 0
(-2975 2675);
DISPLAY 0.872340 (-2975 2675);
DISPLAY INVISIBLE (-2975 2675);
FORCEPROP 1 LAST PATH I223
J 0
(-3302 2800);
DISPLAY 0.872340 (-3302 2800);
PAINT GREEN (-3302 2800);
DISPLAY INVISIBLE (-3302 2800);
FORCEADD TAP..1
(-3300 2900);
FORCEPROP 3 LASTPIN (-3350 2900) SIG_NAME M_L_CPU0_SB_DQS_DN<6>
J 0
(-3340 2910);
DISPLAY 0.659574 (-3340 2910);
PAINT MONO (-3340 2910);
DISPLAY INVISIBLE (-3340 2910);
FORCEPROP 1 LASTPIN (-3350 2900) BN 6
J 0
(-3362 2908);
DISPLAY 0.489362 (-3362 2908);
PAINT GREEN (-3362 2908);
FORCEPROP 2 LAST CDS_LIB mstr_standard
J 0
(-3300 2900);
DISPLAY 0.723404 (-3300 2900);
PAINT MONO (-3300 2900);
DISPLAY INVISIBLE (-3300 2900);
FORCEPROP 1 LAST BODY_TYPE PLUMBING
J 0
(-3300 2950);
DISPLAY 0.872340 (-3300 2950);
PAINT GREEN (-3300 2950);
DISPLAY INVISIBLE (-3300 2950);
FORCEPROP 1 LAST HDL_TAP TRUE
J 0
(-2975 2775);
DISPLAY 0.872340 (-2975 2775);
DISPLAY INVISIBLE (-2975 2775);
FORCEPROP 1 LAST PATH I224
J 0
(-3302 2900);
DISPLAY 0.872340 (-3302 2900);
PAINT GREEN (-3302 2900);
DISPLAY INVISIBLE (-3302 2900);
FORCEADD TAP..1
(-3300 2700);
FORCEPROP 3 LASTPIN (-3350 2700) SIG_NAME M_L_CPU0_SB_DQS_DN<4>
J 0
(-3340 2710);
DISPLAY 0.659574 (-3340 2710);
PAINT MONO (-3340 2710);
DISPLAY INVISIBLE (-3340 2710);
FORCEPROP 1 LASTPIN (-3350 2700) BN 4
J 0
(-3362 2708);
DISPLAY 0.489362 (-3362 2708);
PAINT GREEN (-3362 2708);
FORCEPROP 2 LAST CDS_LIB mstr_standard
J 0
(-3300 2700);
DISPLAY 0.723404 (-3300 2700);
PAINT MONO (-3300 2700);
DISPLAY INVISIBLE (-3300 2700);
FORCEPROP 1 LAST BODY_TYPE PLUMBING
J 0
(-3300 2750);
DISPLAY 0.872340 (-3300 2750);
PAINT GREEN (-3300 2750);
DISPLAY INVISIBLE (-3300 2750);
FORCEPROP 1 LAST HDL_TAP TRUE
J 0
(-2975 2575);
DISPLAY 0.872340 (-2975 2575);
DISPLAY INVISIBLE (-2975 2575);
FORCEPROP 1 LAST PATH I225
J 0
(-3302 2700);
DISPLAY 0.872340 (-3302 2700);
PAINT GREEN (-3302 2700);
DISPLAY INVISIBLE (-3302 2700);
FORCEADD TAP..1
(-3500 2850);
FORCEPROP 3 LASTPIN (-3550 2850) SIG_NAME M_L_CPU0_SB_DQS_DP<5>
J 0
(-3540 2860);
DISPLAY 0.659574 (-3540 2860);
PAINT MONO (-3540 2860);
DISPLAY INVISIBLE (-3540 2860);
FORCEPROP 1 LASTPIN (-3550 2850) BN 5
J 0
(-3562 2858);
DISPLAY 0.489362 (-3562 2858);
PAINT GREEN (-3562 2858);
FORCEPROP 2 LAST CDS_LIB mstr_standard
J 0
(-3500 2850);
DISPLAY 0.723404 (-3500 2850);
PAINT MONO (-3500 2850);
DISPLAY INVISIBLE (-3500 2850);
FORCEPROP 1 LAST BODY_TYPE PLUMBING
J 0
(-3500 2900);
DISPLAY 0.872340 (-3500 2900);
PAINT GREEN (-3500 2900);
DISPLAY INVISIBLE (-3500 2900);
FORCEPROP 1 LAST HDL_TAP TRUE
J 0
(-3175 2725);
DISPLAY 0.872340 (-3175 2725);
DISPLAY INVISIBLE (-3175 2725);
FORCEPROP 1 LAST PATH I226
J 0
(-3502 2850);
DISPLAY 0.872340 (-3502 2850);
PAINT GREEN (-3502 2850);
DISPLAY INVISIBLE (-3502 2850);
FORCEADD TAP..1
(-3500 2750);
FORCEPROP 3 LASTPIN (-3550 2750) SIG_NAME M_L_CPU0_SB_DQS_DP<4>
J 0
(-3540 2760);
DISPLAY 0.659574 (-3540 2760);
PAINT MONO (-3540 2760);
DISPLAY INVISIBLE (-3540 2760);
FORCEPROP 1 LASTPIN (-3550 2750) BN 4
J 0
(-3562 2758);
DISPLAY 0.489362 (-3562 2758);
PAINT GREEN (-3562 2758);
FORCEPROP 2 LAST CDS_LIB mstr_standard
J 0
(-3500 2750);
DISPLAY 0.723404 (-3500 2750);
PAINT MONO (-3500 2750);
DISPLAY INVISIBLE (-3500 2750);
FORCEPROP 1 LAST BODY_TYPE PLUMBING
J 0
(-3500 2800);
DISPLAY 0.872340 (-3500 2800);
PAINT GREEN (-3500 2800);
DISPLAY INVISIBLE (-3500 2800);
FORCEPROP 1 LAST HDL_TAP TRUE
J 0
(-3175 2625);
DISPLAY 0.872340 (-3175 2625);
DISPLAY INVISIBLE (-3175 2625);
FORCEPROP 1 LAST PATH I227
J 0
(-3502 2750);
DISPLAY 0.872340 (-3502 2750);
PAINT GREEN (-3502 2750);
DISPLAY INVISIBLE (-3502 2750);
FORCEADD TAP..1
(-3300 2500);
FORCEPROP 3 LASTPIN (-3350 2500) SIG_NAME M_L_CPU0_SB_DQS_DN<2>
J 0
(-3340 2510);
DISPLAY 0.659574 (-3340 2510);
PAINT MONO (-3340 2510);
DISPLAY INVISIBLE (-3340 2510);
FORCEPROP 1 LASTPIN (-3350 2500) BN 2
J 0
(-3362 2508);
DISPLAY 0.489362 (-3362 2508);
PAINT GREEN (-3362 2508);
FORCEPROP 2 LAST CDS_LIB mstr_standard
J 0
(-3300 2500);
DISPLAY 0.723404 (-3300 2500);
PAINT MONO (-3300 2500);
DISPLAY INVISIBLE (-3300 2500);
FORCEPROP 1 LAST BODY_TYPE PLUMBING
J 0
(-3300 2550);
DISPLAY 0.872340 (-3300 2550);
PAINT GREEN (-3300 2550);
DISPLAY INVISIBLE (-3300 2550);
FORCEPROP 1 LAST HDL_TAP TRUE
J 0
(-2975 2375);
DISPLAY 0.872340 (-2975 2375);
DISPLAY INVISIBLE (-2975 2375);
FORCEPROP 1 LAST PATH I228
J 0
(-3302 2500);
DISPLAY 0.872340 (-3302 2500);
PAINT GREEN (-3302 2500);
DISPLAY INVISIBLE (-3302 2500);
FORCEADD TAP..1
(-3300 2600);
FORCEPROP 3 LASTPIN (-3350 2600) SIG_NAME M_L_CPU0_SB_DQS_DN<3>
J 0
(-3340 2610);
DISPLAY 0.659574 (-3340 2610);
PAINT MONO (-3340 2610);
DISPLAY INVISIBLE (-3340 2610);
FORCEPROP 1 LASTPIN (-3350 2600) BN 3
J 0
(-3362 2608);
DISPLAY 0.489362 (-3362 2608);
PAINT GREEN (-3362 2608);
FORCEPROP 2 LAST CDS_LIB mstr_standard
J 0
(-3300 2600);
DISPLAY 0.723404 (-3300 2600);
PAINT MONO (-3300 2600);
DISPLAY INVISIBLE (-3300 2600);
FORCEPROP 1 LAST BODY_TYPE PLUMBING
J 0
(-3300 2650);
DISPLAY 0.872340 (-3300 2650);
PAINT GREEN (-3300 2650);
DISPLAY INVISIBLE (-3300 2650);
FORCEPROP 1 LAST HDL_TAP TRUE
J 0
(-2975 2475);
DISPLAY 0.872340 (-2975 2475);
DISPLAY INVISIBLE (-2975 2475);
FORCEPROP 1 LAST PATH I229
J 0
(-3302 2600);
DISPLAY 0.872340 (-3302 2600);
PAINT GREEN (-3302 2600);
DISPLAY INVISIBLE (-3302 2600);
FORCEADD TAP..1
R 2
(-7725 2875);
FORCEPROP 3 LASTPIN (-7675 2875) SIG_NAME M_L_CPU0_SB_CB<0>
J 0
(-7665 2885);
DISPLAY 0.659574 (-7665 2885);
PAINT MONO (-7665 2885);
DISPLAY INVISIBLE (-7665 2885);
FORCEPROP 1 LASTPIN (-7675 2875) BN 0
J 2
(-7663 2883);
DISPLAY 0.489362 (-7663 2883);
PAINT GREEN (-7663 2883);
FORCEPROP 2 LAST CDS_LIB mstr_standard
J 0
(-7725 2875);
DISPLAY 0.723404 (-7725 2875);
PAINT MONO (-7725 2875);
DISPLAY INVISIBLE (-7725 2875);
FORCEPROP 1 LAST BODY_TYPE PLUMBING
J 2
(-7725 2925);
DISPLAY 0.872340 (-7725 2925);
PAINT GREEN (-7725 2925);
DISPLAY INVISIBLE (-7725 2925);
FORCEPROP 1 LAST HDL_TAP TRUE
J 2
(-8050 2750);
DISPLAY 0.872340 (-8050 2750);
DISPLAY INVISIBLE (-8050 2750);
FORCEPROP 1 LAST PATH I23
J 2
(-7723 2875);
DISPLAY 0.872340 (-7723 2875);
PAINT GREEN (-7723 2875);
DISPLAY INVISIBLE (-7723 2875);
FORCEADD TAP..1
(-3300 2400);
FORCEPROP 3 LASTPIN (-3350 2400) SIG_NAME M_L_CPU0_SB_DQS_DN<1>
J 0
(-3340 2410);
DISPLAY 0.659574 (-3340 2410);
PAINT MONO (-3340 2410);
DISPLAY INVISIBLE (-3340 2410);
FORCEPROP 1 LASTPIN (-3350 2400) BN 1
J 0
(-3362 2408);
DISPLAY 0.489362 (-3362 2408);
PAINT GREEN (-3362 2408);
FORCEPROP 2 LAST CDS_LIB mstr_standard
J 0
(-3300 2400);
DISPLAY 0.723404 (-3300 2400);
PAINT MONO (-3300 2400);
DISPLAY INVISIBLE (-3300 2400);
FORCEPROP 1 LAST BODY_TYPE PLUMBING
J 0
(-3300 2450);
DISPLAY 0.872340 (-3300 2450);
PAINT GREEN (-3300 2450);
DISPLAY INVISIBLE (-3300 2450);
FORCEPROP 1 LAST HDL_TAP TRUE
J 0
(-2975 2275);
DISPLAY 0.872340 (-2975 2275);
DISPLAY INVISIBLE (-2975 2275);
FORCEPROP 1 LAST PATH I230
J 0
(-3302 2400);
DISPLAY 0.872340 (-3302 2400);
PAINT GREEN (-3302 2400);
DISPLAY INVISIBLE (-3302 2400);
FORCEADD TAP..1
(-3500 2650);
FORCEPROP 3 LASTPIN (-3550 2650) SIG_NAME M_L_CPU0_SB_DQS_DP<3>
J 0
(-3540 2660);
DISPLAY 0.659574 (-3540 2660);
PAINT MONO (-3540 2660);
DISPLAY INVISIBLE (-3540 2660);
FORCEPROP 1 LASTPIN (-3550 2650) BN 3
J 0
(-3562 2658);
DISPLAY 0.489362 (-3562 2658);
PAINT GREEN (-3562 2658);
FORCEPROP 2 LAST CDS_LIB mstr_standard
J 0
(-3500 2650);
DISPLAY 0.723404 (-3500 2650);
PAINT MONO (-3500 2650);
DISPLAY INVISIBLE (-3500 2650);
FORCEPROP 1 LAST BODY_TYPE PLUMBING
J 0
(-3500 2700);
DISPLAY 0.872340 (-3500 2700);
PAINT GREEN (-3500 2700);
DISPLAY INVISIBLE (-3500 2700);
FORCEPROP 1 LAST HDL_TAP TRUE
J 0
(-3175 2525);
DISPLAY 0.872340 (-3175 2525);
DISPLAY INVISIBLE (-3175 2525);
FORCEPROP 1 LAST PATH I231
J 0
(-3502 2650);
DISPLAY 0.872340 (-3502 2650);
PAINT GREEN (-3502 2650);
DISPLAY INVISIBLE (-3502 2650);
FORCEADD TAP..1
(-3500 2550);
FORCEPROP 3 LASTPIN (-3550 2550) SIG_NAME M_L_CPU0_SB_DQS_DP<2>
J 0
(-3540 2560);
DISPLAY 0.659574 (-3540 2560);
PAINT MONO (-3540 2560);
DISPLAY INVISIBLE (-3540 2560);
FORCEPROP 1 LASTPIN (-3550 2550) BN 2
J 0
(-3562 2558);
DISPLAY 0.489362 (-3562 2558);
PAINT GREEN (-3562 2558);
FORCEPROP 2 LAST CDS_LIB mstr_standard
J 0
(-3500 2550);
DISPLAY 0.723404 (-3500 2550);
PAINT MONO (-3500 2550);
DISPLAY INVISIBLE (-3500 2550);
FORCEPROP 1 LAST BODY_TYPE PLUMBING
J 0
(-3500 2600);
DISPLAY 0.872340 (-3500 2600);
PAINT GREEN (-3500 2600);
DISPLAY INVISIBLE (-3500 2600);
FORCEPROP 1 LAST HDL_TAP TRUE
J 0
(-3175 2425);
DISPLAY 0.872340 (-3175 2425);
DISPLAY INVISIBLE (-3175 2425);
FORCEPROP 1 LAST PATH I232
J 0
(-3502 2550);
DISPLAY 0.872340 (-3502 2550);
PAINT GREEN (-3502 2550);
DISPLAY INVISIBLE (-3502 2550);
FORCEADD TAP..1
(-3500 2450);
FORCEPROP 3 LASTPIN (-3550 2450) SIG_NAME M_L_CPU0_SB_DQS_DP<1>
J 0
(-3540 2460);
DISPLAY 0.659574 (-3540 2460);
PAINT MONO (-3540 2460);
DISPLAY INVISIBLE (-3540 2460);
FORCEPROP 1 LASTPIN (-3550 2450) BN 1
J 0
(-3562 2458);
DISPLAY 0.489362 (-3562 2458);
PAINT GREEN (-3562 2458);
FORCEPROP 2 LAST CDS_LIB mstr_standard
J 0
(-3500 2450);
DISPLAY 0.723404 (-3500 2450);
PAINT MONO (-3500 2450);
DISPLAY INVISIBLE (-3500 2450);
FORCEPROP 1 LAST BODY_TYPE PLUMBING
J 0
(-3500 2500);
DISPLAY 0.872340 (-3500 2500);
PAINT GREEN (-3500 2500);
DISPLAY INVISIBLE (-3500 2500);
FORCEPROP 1 LAST HDL_TAP TRUE
J 0
(-3175 2325);
DISPLAY 0.872340 (-3175 2325);
DISPLAY INVISIBLE (-3175 2325);
FORCEPROP 1 LAST PATH I233
J 0
(-3502 2450);
DISPLAY 0.872340 (-3502 2450);
PAINT GREEN (-3502 2450);
DISPLAY INVISIBLE (-3502 2450);
FORCEADD TAP..1
(-3300 2300);
FORCEPROP 3 LASTPIN (-3350 2300) SIG_NAME M_L_CPU0_SB_DQS_DN<0>
J 0
(-3340 2310);
DISPLAY 0.659574 (-3340 2310);
PAINT MONO (-3340 2310);
DISPLAY INVISIBLE (-3340 2310);
FORCEPROP 1 LASTPIN (-3350 2300) BN 0
J 0
(-3362 2308);
DISPLAY 0.489362 (-3362 2308);
PAINT GREEN (-3362 2308);
FORCEPROP 2 LAST CDS_LIB mstr_standard
J 0
(-3300 2300);
DISPLAY 0.723404 (-3300 2300);
PAINT MONO (-3300 2300);
DISPLAY INVISIBLE (-3300 2300);
FORCEPROP 1 LAST BODY_TYPE PLUMBING
J 0
(-3300 2350);
DISPLAY 0.872340 (-3300 2350);
PAINT GREEN (-3300 2350);
DISPLAY INVISIBLE (-3300 2350);
FORCEPROP 1 LAST HDL_TAP TRUE
J 0
(-2975 2175);
DISPLAY 0.872340 (-2975 2175);
DISPLAY INVISIBLE (-2975 2175);
FORCEPROP 1 LAST PATH I234
J 0
(-3302 2300);
DISPLAY 0.872340 (-3302 2300);
PAINT GREEN (-3302 2300);
DISPLAY INVISIBLE (-3302 2300);
FORCEADD TAP..1
(-3500 2350);
FORCEPROP 3 LASTPIN (-3550 2350) SIG_NAME M_L_CPU0_SB_DQS_DP<0>
J 0
(-3540 2360);
DISPLAY 0.659574 (-3540 2360);
PAINT MONO (-3540 2360);
DISPLAY INVISIBLE (-3540 2360);
FORCEPROP 1 LASTPIN (-3550 2350) BN 0
J 0
(-3562 2358);
DISPLAY 0.489362 (-3562 2358);
PAINT GREEN (-3562 2358);
FORCEPROP 2 LAST CDS_LIB mstr_standard
J 0
(-3500 2350);
DISPLAY 0.723404 (-3500 2350);
PAINT MONO (-3500 2350);
DISPLAY INVISIBLE (-3500 2350);
FORCEPROP 1 LAST BODY_TYPE PLUMBING
J 0
(-3500 2400);
DISPLAY 0.872340 (-3500 2400);
PAINT GREEN (-3500 2400);
DISPLAY INVISIBLE (-3500 2400);
FORCEPROP 1 LAST HDL_TAP TRUE
J 0
(-3175 2225);
DISPLAY 0.872340 (-3175 2225);
DISPLAY INVISIBLE (-3175 2225);
FORCEPROP 1 LAST PATH I235
J 0
(-3502 2350);
DISPLAY 0.872340 (-3502 2350);
PAINT GREEN (-3502 2350);
DISPLAY INVISIBLE (-3502 2350);
FORCEADD SCONN288_DDR506112002KQ..2
(-4450 3300);
FORCEPROP 1 LAST LOCATION J67
J 0
(-5050 4625);
DISPLAY 0.468085 (-5050 4625);
PAINT SKYBLUE (-5050 4625);
FORCEPROP 0 LAST $SEC 2
J 0
(-4900 4775);
DISPLAY 0.680851 (-4900 4775);
PAINT MONO (-4900 4775);
DISPLAY INVISIBLE (-4900 4775);
FORCEPROP 0 LAST CDS_SEC 2
J 0
(-4900 4775);
DISPLAY 1.021277 (-4900 4775);
DISPLAY INVISIBLE (-4900 4775);
FORCEPROP 0 LASTPIN (-3700 3350) $PN 12
J 0
(-3690 3360);
DISPLAY 0.680851 (-3690 3360);
PAINT MONO (-3690 3360);
FORCEPROP 0 LASTPIN (-3700 3400) $PN 11
J 0
(-3690 3410);
DISPLAY 0.680851 (-3690 3410);
PAINT MONO (-3690 3410);
FORCEPROP 0 LASTPIN (-3700 2300) $PN 105
J 0
(-3690 2310);
DISPLAY 0.680851 (-3690 2310);
PAINT MONO (-3690 2310);
FORCEPROP 0 LASTPIN (-3700 2350) $PN 104
J 0
(-3690 2360);
DISPLAY 0.680851 (-3690 2360);
PAINT MONO (-3690 2360);
FORCEPROP 0 LASTPIN (-3700 3450) $PN 23
J 0
(-3690 3460);
DISPLAY 0.680851 (-3690 3460);
PAINT MONO (-3690 3460);
FORCEPROP 0 LASTPIN (-3700 3500) $PN 22
J 0
(-3690 3510);
DISPLAY 0.680851 (-3690 3510);
PAINT MONO (-3690 3510);
FORCEPROP 0 LASTPIN (-3700 2400) $PN 116
J 0
(-3690 2410);
DISPLAY 0.680851 (-3690 2410);
PAINT MONO (-3690 2410);
FORCEPROP 0 LASTPIN (-3700 2450) $PN 115
J 0
(-3690 2460);
DISPLAY 0.680851 (-3690 2460);
PAINT MONO (-3690 2460);
FORCEPROP 0 LASTPIN (-3700 3550) $PN 34
J 0
(-3690 3560);
DISPLAY 0.680851 (-3690 3560);
PAINT MONO (-3690 3560);
FORCEPROP 0 LASTPIN (-3700 3600) $PN 33
J 0
(-3690 3610);
DISPLAY 0.680851 (-3690 3610);
PAINT MONO (-3690 3610);
FORCEPROP 0 LASTPIN (-3700 2500) $PN 127
J 0
(-3690 2510);
DISPLAY 0.680851 (-3690 2510);
PAINT MONO (-3690 2510);
FORCEPROP 0 LASTPIN (-3700 2550) $PN 126
J 0
(-3690 2560);
DISPLAY 0.680851 (-3690 2560);
PAINT MONO (-3690 2560);
FORCEPROP 0 LASTPIN (-3700 3650) $PN 45
J 0
(-3690 3660);
DISPLAY 0.680851 (-3690 3660);
PAINT MONO (-3690 3660);
FORCEPROP 0 LASTPIN (-3700 3700) $PN 44
J 0
(-3690 3710);
DISPLAY 0.680851 (-3690 3710);
PAINT MONO (-3690 3710);
FORCEPROP 0 LASTPIN (-3700 2600) $PN 138
J 0
(-3690 2610);
DISPLAY 0.680851 (-3690 2610);
PAINT MONO (-3690 2610);
FORCEPROP 0 LASTPIN (-3700 2650) $PN 137
J 0
(-3690 2660);
DISPLAY 0.680851 (-3690 2660);
PAINT MONO (-3690 2660);
FORCEPROP 0 LASTPIN (-3700 3750) $PN 56
J 0
(-3690 3760);
DISPLAY 0.680851 (-3690 3760);
PAINT MONO (-3690 3760);
FORCEPROP 0 LASTPIN (-3700 3800) $PN 55
J 0
(-3690 3810);
DISPLAY 0.680851 (-3690 3810);
PAINT MONO (-3690 3810);
FORCEPROP 0 LASTPIN (-3700 2700) $PN 238
J 0
(-3690 2710);
DISPLAY 0.680851 (-3690 2710);
PAINT MONO (-3690 2710);
FORCEPROP 0 LASTPIN (-3700 2750) $PN 239
J 0
(-3690 2760);
DISPLAY 0.680851 (-3690 2760);
PAINT MONO (-3690 2760);
FORCEPROP 0 LASTPIN (-3700 3850) $PN 156
J 0
(-3690 3860);
DISPLAY 0.680851 (-3690 3860);
PAINT MONO (-3690 3860);
FORCEPROP 0 LASTPIN (-3700 3900) $PN 157
J 0
(-3690 3910);
DISPLAY 0.680851 (-3690 3910);
PAINT MONO (-3690 3910);
FORCEPROP 0 LASTPIN (-3700 2800) $PN 249
J 0
(-3690 2810);
DISPLAY 0.680851 (-3690 2810);
PAINT MONO (-3690 2810);
FORCEPROP 0 LASTPIN (-3700 2850) $PN 250
J 0
(-3690 2860);
DISPLAY 0.680851 (-3690 2860);
PAINT MONO (-3690 2860);
FORCEPROP 0 LASTPIN (-3700 3950) $PN 167
J 0
(-3690 3960);
DISPLAY 0.680851 (-3690 3960);
PAINT MONO (-3690 3960);
FORCEPROP 0 LASTPIN (-3700 4000) $PN 168
J 0
(-3690 4010);
DISPLAY 0.680851 (-3690 4010);
PAINT MONO (-3690 4010);
FORCEPROP 0 LASTPIN (-3700 2900) $PN 260
J 0
(-3690 2910);
DISPLAY 0.680851 (-3690 2910);
PAINT MONO (-3690 2910);
FORCEPROP 0 LASTPIN (-3700 2950) $PN 261
J 0
(-3690 2960);
DISPLAY 0.680851 (-3690 2960);
PAINT MONO (-3690 2960);
FORCEPROP 0 LASTPIN (-3700 4050) $PN 178
J 0
(-3690 4060);
DISPLAY 0.680851 (-3690 4060);
PAINT MONO (-3690 4060);
FORCEPROP 0 LASTPIN (-3700 4100) $PN 179
J 0
(-3690 4110);
DISPLAY 0.680851 (-3690 4110);
PAINT MONO (-3690 4110);
FORCEPROP 0 LASTPIN (-3700 3000) $PN 271
J 0
(-3690 3010);
DISPLAY 0.680851 (-3690 3010);
PAINT MONO (-3690 3010);
FORCEPROP 0 LASTPIN (-3700 3050) $PN 272
J 0
(-3690 3060);
DISPLAY 0.680851 (-3690 3060);
PAINT MONO (-3690 3060);
FORCEPROP 0 LASTPIN (-3700 4150) $PN 189
J 0
(-3690 4160);
DISPLAY 0.680851 (-3690 4160);
PAINT MONO (-3690 4160);
FORCEPROP 0 LASTPIN (-3700 4200) $PN 190
J 0
(-3690 4210);
DISPLAY 0.680851 (-3690 4210);
PAINT MONO (-3690 4210);
FORCEPROP 0 LASTPIN (-3700 3100) $PN 282
J 0
(-3690 3110);
DISPLAY 0.680851 (-3690 3110);
PAINT MONO (-3690 3110);
FORCEPROP 0 LASTPIN (-3700 3150) $PN 283
J 0
(-3690 3160);
DISPLAY 0.680851 (-3690 3160);
PAINT MONO (-3690 3160);
FORCEPROP 0 LASTPIN (-3700 4250) $PN 200
J 0
(-3690 4260);
DISPLAY 0.680851 (-3690 4260);
PAINT MONO (-3690 4260);
FORCEPROP 0 LASTPIN (-3700 4300) $PN 201
J 0
(-3690 4310);
DISPLAY 0.680851 (-3690 4310);
PAINT MONO (-3690 4310);
FORCEPROP 0 LASTPIN (-3700 3200) $PN 94
J 0
(-3690 3210);
DISPLAY 0.680851 (-3690 3210);
PAINT MONO (-3690 3210);
FORCEPROP 0 LASTPIN (-3700 3250) $PN 93
J 0
(-3690 3260);
DISPLAY 0.680851 (-3690 3260);
PAINT MONO (-3690 3260);
FORCEPROP 2 LAST PART_TYPE SMLF
J 0
(-4900 4725);
DISPLAY 1.021277 (-4900 4725);
FORCEPROP 2 LAST VALUE SCONN288_DDR506112002KQ
J 0
(-4900 4675);
DISPLAY 0.489362 (-4900 4675);
PAINT SKYBLUE (-4900 4675);
FORCEPROP 1 LAST MATERIAL IO
J 0
(-5050 4475);
DISPLAY 0.468085 (-5050 4475);
PAINT SKYBLUE (-5050 4475);
FORCEPROP 1 LAST PART_NUMBER DFHST8FS479
J 0
(-5050 4550);
DISPLAY 0.468085 (-5050 4550);
PAINT SKYBLUE (-5050 4550);
FORCEPROP 1 LAST CDS_LMAN_SYM_OUTLINE -600,1150,600,-1150
J 0
(-4450 3300);
DISPLAY 0.468085 (-4450 3300);
PAINT GREEN (-4450 3300);
DISPLAY INVISIBLE (-4450 3300);
FORCEPROP 1 LAST PATH I236
J 0
(-4450 3300);
DISPLAY 0.723404 (-4450 3300);
PAINT GREEN (-4450 3300);
DISPLAY INVISIBLE (-4450 3300);
FORCEPROP 1 LAST NEEDS_NO_SIZE TRUE
J 0
(-4450 3300);
DISPLAY 0.723404 (-4450 3300);
PAINT GREEN (-4450 3300);
DISPLAY INVISIBLE (-4450 3300);
FORCEPROP 2 LAST CDS_LIB pure_quanta
J 0
(-4450 3300);
DISPLAY INVISIBLE (-4450 3300);
FORCEADD GND..1
(-2900 5250);
FORCEPROP 3 LASTPIN (-2900 5300) SIG_NAME GND\g
J 0
(-2890 5310);
DISPLAY 0.659574 (-2890 5310);
PAINT MONO (-2890 5310);
DISPLAY INVISIBLE (-2890 5310);
FORCEPROP 1 LAST SIZE 1B
J 0
(-2825 5200);
DISPLAY 0.723404 (-2825 5200);
PAINT GREEN (-2825 5200);
DISPLAY INVISIBLE (-2825 5200);
FORCEPROP 2 LAST BOM_COST MEM
J 0
(-2875 5375);
DISPLAY 0.659574 (-2875 5375);
DISPLAY INVISIBLE (-2875 5375);
FORCEPROP 2 LAST CDS_LIB pure_quanta_power
J 0
(-2900 5250);
DISPLAY INVISIBLE (-2900 5250);
FORCEPROP 1 LAST PATH I237
J 0
(-2825 5250);
DISPLAY 0.872340 (-2825 5250);
PAINT AQUA (-2825 5250);
DISPLAY INVISIBLE (-2825 5250);
FORCEPROP 2 LAST ROOM MEM_EFGH_DECOUPLING_CAPS
J 0
(-2875 5325);
DISPLAY 0.659574 (-2875 5325);
PAINT RED (-2875 5325);
DISPLAY INVISIBLE (-2875 5325);
FORCEPROP 1 LAST HDL_POWER GND
J 0
(-2900 5400);
DISPLAY 0.723404 (-2900 5400);
PAINT GREEN (-2900 5400);
DISPLAY INVISIBLE (-2900 5400);
FORCEADD Q_CAP..1
R 2
(-2900 5600);
FORCEPROP 1 LAST LOCATION C170
J 2
(-2950 5700);
DISPLAY 0.489362 (-2950 5700);
PAINT SKYBLUE (-2950 5700);
FORCEPROP 0 LAST $SEC 1
J 0
(-2950 5750);
DISPLAY 0.680851 (-2950 5750);
PAINT MONO (-2950 5750);
DISPLAY INVISIBLE (-2950 5750);
FORCEPROP 0 LAST CDS_SEC 1
J 0
(-2950 5750);
DISPLAY 0.680851 (-2950 5750);
DISPLAY INVISIBLE (-2950 5750);
FORCEPROP 1 LASTPIN (-2900 5700) $PN 1
J 2
(-2910 5680);
DISPLAY 0.489362 (-2910 5680);
PAINT MONO (-2910 5680);
FORCEPROP 1 LASTPIN (-2900 5500) $PN 2
J 2
(-2910 5480);
DISPLAY 0.489362 (-2910 5480);
PAINT MONO (-2910 5480);
FORCEPROP 1 LAST VALUE 10UF
J 2
(-2950 5650);
DISPLAY 0.489362 (-2950 5650);
PAINT SKYBLUE (-2950 5650);
FORCEPROP 1 LAST PART_NUMBER CH6104KEA00
J 2
(-2950 5450);
DISPLAY 0.489362 (-2950 5450);
PAINT SKYBLUE (-2950 5450);
FORCEPROP 1 LAST VOLTAGE 25V
J 2
(-2950 5600);
DISPLAY 0.489362 (-2950 5600);
PAINT SKYBLUE (-2950 5600);
FORCEPROP 1 LAST PACK_TYPE C0805
J 2
(-2950 5400);
DISPLAY 0.489362 (-2950 5400);
PAINT SKYBLUE (-2950 5400);
FORCEPROP 1 LAST MATERIAL X6S
J 2
(-2950 5500);
DISPLAY 0.489362 (-2950 5500);
PAINT SKYBLUE (-2950 5500);
FORCEPROP 1 LAST TOLERANCE 10%
J 2
(-2950 5550);
DISPLAY 0.489362 (-2950 5550);
PAINT SKYBLUE (-2950 5550);
FORCEPROP 2 LAST CDS_LIB pure_quanta
J 0
(-2900 5600);
DISPLAY INVISIBLE (-2900 5600);
FORCEPROP 0 LAST BOM_COST MEM
J 2
(-2955 5745);
DISPLAY 0.595745 (-2955 5745);
PAINT MONO (-2955 5745);
DISPLAY INVISIBLE (-2955 5745);
FORCEPROP 1 LAST PATH I238
J 2
(-2950 5750);
DISPLAY 0.978723 (-2950 5750);
PAINT WHITE (-2950 5750);
DISPLAY INVISIBLE (-2950 5750);
FORCEPROP 0 LAST ROOM MEM_CH_A_CPU0_DIMM1
J 2
(-2955 5745);
DISPLAY 0.595745 (-2955 5745);
PAINT RED (-2955 5745);
DISPLAY INVISIBLE (-2955 5745);
FORCEADD Q_CAP..1
R 2
(-2325 5600);
FORCEPROP 1 LAST LOCATION C171
J 2
(-2375 5700);
DISPLAY 0.489362 (-2375 5700);
PAINT SKYBLUE (-2375 5700);
FORCEPROP 0 LAST $SEC 1
J 0
(-2375 5750);
DISPLAY 0.680851 (-2375 5750);
PAINT MONO (-2375 5750);
DISPLAY INVISIBLE (-2375 5750);
FORCEPROP 0 LAST CDS_SEC 1
J 0
(-2375 5750);
DISPLAY 0.680851 (-2375 5750);
DISPLAY INVISIBLE (-2375 5750);
FORCEPROP 1 LASTPIN (-2325 5700) $PN 1
J 2
(-2335 5680);
DISPLAY 0.489362 (-2335 5680);
PAINT MONO (-2335 5680);
FORCEPROP 1 LASTPIN (-2325 5500) $PN 2
J 2
(-2335 5480);
DISPLAY 0.489362 (-2335 5480);
PAINT MONO (-2335 5480);
FORCEPROP 1 LAST TOLERANCE 10%
J 2
(-2375 5550);
DISPLAY 0.489362 (-2375 5550);
PAINT SKYBLUE (-2375 5550);
FORCEPROP 1 LAST VALUE 10UF
J 2
(-2375 5650);
DISPLAY 0.489362 (-2375 5650);
PAINT SKYBLUE (-2375 5650);
FORCEPROP 1 LAST VOLTAGE 25V
J 2
(-2375 5600);
DISPLAY 0.489362 (-2375 5600);
PAINT SKYBLUE (-2375 5600);
FORCEPROP 1 LAST PACK_TYPE C0805
J 2
(-2375 5400);
DISPLAY 0.489362 (-2375 5400);
PAINT SKYBLUE (-2375 5400);
FORCEPROP 1 LAST MATERIAL X6S
J 2
(-2375 5500);
DISPLAY 0.489362 (-2375 5500);
PAINT SKYBLUE (-2375 5500);
FORCEPROP 1 LAST PART_NUMBER CH6104KEA00
J 2
(-2375 5450);
DISPLAY 0.489362 (-2375 5450);
PAINT SKYBLUE (-2375 5450);
FORCEPROP 2 LAST CDS_LIB pure_quanta
J 0
(-2325 5600);
DISPLAY INVISIBLE (-2325 5600);
FORCEPROP 0 LAST BOM_COST MEM
J 2
(-2380 5745);
DISPLAY 0.595745 (-2380 5745);
PAINT MONO (-2380 5745);
DISPLAY INVISIBLE (-2380 5745);
FORCEPROP 1 LAST PATH I239
J 2
(-2375 5750);
DISPLAY 0.978723 (-2375 5750);
PAINT WHITE (-2375 5750);
DISPLAY INVISIBLE (-2375 5750);
FORCEPROP 0 LAST ROOM MEM_CH_A_CPU0_DIMM1
J 2
(-2380 5745);
DISPLAY 0.595745 (-2380 5745);
PAINT RED (-2380 5745);
DISPLAY INVISIBLE (-2380 5745);
FORCEADD TAP..1
R 2
(-7725 2925);
FORCEPROP 3 LASTPIN (-7675 2925) SIG_NAME M_L_CPU0_SB_CB<1>
J 0
(-7665 2935);
DISPLAY 0.659574 (-7665 2935);
PAINT MONO (-7665 2935);
DISPLAY INVISIBLE (-7665 2935);
FORCEPROP 1 LASTPIN (-7675 2925) BN 1
J 2
(-7663 2933);
DISPLAY 0.489362 (-7663 2933);
PAINT GREEN (-7663 2933);
FORCEPROP 2 LAST CDS_LIB mstr_standard
J 0
(-7725 2925);
DISPLAY 0.723404 (-7725 2925);
PAINT MONO (-7725 2925);
DISPLAY INVISIBLE (-7725 2925);
FORCEPROP 1 LAST BODY_TYPE PLUMBING
J 2
(-7725 2975);
DISPLAY 0.872340 (-7725 2975);
PAINT GREEN (-7725 2975);
DISPLAY INVISIBLE (-7725 2975);
FORCEPROP 1 LAST HDL_TAP TRUE
J 2
(-8050 2800);
DISPLAY 0.872340 (-8050 2800);
DISPLAY INVISIBLE (-8050 2800);
FORCEPROP 1 LAST PATH I24
J 2
(-7723 2925);
DISPLAY 0.872340 (-7723 2925);
PAINT GREEN (-7723 2925);
DISPLAY INVISIBLE (-7723 2925);
FORCEADD UNIVERSAL_POWER..1
(-2900 5925);
FORCEPROP 3 LASTPIN (-2900 5875) SIG_NAME P12V_MEM_0\g
J 0
(-2890 5885);
DISPLAY 0.659574 (-2890 5885);
PAINT MONO (-2890 5885);
DISPLAY INVISIBLE (-2890 5885);
FORCEPROP 1 LAST HDL_POWER P12V_MEM_0
J 1
(-2925 5975);
DISPLAY 0.489362 (-2925 5975);
PAINT GREEN (-2925 5975);
FORCEPROP 2 LAST CDS_LIB pure_quanta_power
J 0
(-2900 5925);
DISPLAY INVISIBLE (-2900 5925);
FORCEPROP 2 LAST BOM_COST VR_SYSTEM
J 0
(-2900 6025);
DISPLAY 0.617021 (-2900 6025);
PAINT PURPLE (-2900 6025);
DISPLAY INVISIBLE (-2900 6025);
FORCEPROP 1 LAST PATH I240
J 0
(-2850 5950);
DISPLAY 0.872340 (-2850 5950);
PAINT AQUA (-2850 5950);
DISPLAY INVISIBLE (-2850 5950);
FORCEADD OFFPAGE..1
(-8350 2375);
FORCEPROP 2 LAST $XR5 95 
J 0
(-9052 2375);
DISPLAY 0.638298 (-9052 2375);
PAINT MONO (-9052 2375);
FORCEPROP 2 LAST $XR4 94 
J 0
(-8962 2375);
DISPLAY 0.638298 (-8962 2375);
PAINT MONO (-8962 2375);
FORCEPROP 2 LAST $XR3 93 
J 0
(-8872 2375);
DISPLAY 0.638298 (-8872 2375);
PAINT MONO (-8872 2375);
FORCEPROP 2 LAST $XR2 92 
J 0
(-8782 2375);
DISPLAY 0.638298 (-8782 2375);
PAINT MONO (-8782 2375);
FORCEPROP 2 LAST $XR1 91 
J 0
(-8692 2375);
DISPLAY 0.638298 (-8692 2375);
PAINT MONO (-8692 2375);
FORCEPROP 2 LAST $XR0 136 
J 0
(-8602 2375);
DISPLAY 0.638298 (-8602 2375);
PAINT MONO (-8602 2375);
FORCEPROP 2 LAST PATH I241
J 0
(-8625 2425);
DISPLAY 0.680851 (-8625 2425);
DISPLAY INVISIBLE (-8625 2425);
FORCEPROP 2 LAST CDS_LIB mstr_standard
J 0
(-8350 2375);
DISPLAY 0.808511 (-8350 2375);
DISPLAY INVISIBLE (-8350 2375);
FORCEPROP 1 LAST OFFPAGE TRUE
J 0
(-8025 2250);
DISPLAY 0.872340 (-8025 2250);
PAINT GREEN (-8025 2250);
DISPLAY INVISIBLE (-8025 2250);
FORCEPROP 1 LAST COMMENT_BODY TRUE
J 0
(-8225 2275);
DISPLAY 0.872340 (-8225 2275);
PAINT GREEN (-8225 2275);
DISPLAY INVISIBLE (-8225 2275);
FORCEADD Q_RES..1
(-7775 2375);
FORCEPROP 1 LAST $LOCATION R1579
J 0
(-7825 2400);
DISPLAY 0.638298 (-7825 2400);
PAINT SKYBLUE (-7825 2400);
FORCEPROP 0 LAST CDS_LOCATION R1579
J 0
(-7825 2475);
DISPLAY 0.680851 (-7825 2475);
DISPLAY INVISIBLE (-7825 2475);
FORCEPROP 0 LAST $SEC 1
J 0
(-7825 2475);
DISPLAY 0.680851 (-7825 2475);
PAINT MONO (-7825 2475);
DISPLAY INVISIBLE (-7825 2475);
FORCEPROP 0 LAST CDS_SEC 1
J 0
(-7825 2475);
DISPLAY 0.680851 (-7825 2475);
DISPLAY INVISIBLE (-7825 2475);
FORCEPROP 1 LASTPIN (-7875 2375) $PN 1
J 0
(-7863 2387);
DISPLAY 0.787234 (-7863 2387);
PAINT MONO (-7863 2387);
FORCEPROP 1 LASTPIN (-7675 2375) $PN 2
J 0
(-7713 2387);
DISPLAY 0.787234 (-7713 2387);
PAINT MONO (-7713 2387);
FORCEPROP 1 LAST VALUE 49.9
J 2
(-7600 2425);
DISPLAY 0.510638 (-7600 2425);
PAINT SKYBLUE (-7600 2425);
FORCEPROP 1 LAST PART_NUMBER CS04992FB07
J 0
(-7825 2475);
DISPLAY 0.978723 (-7825 2475);
DISPLAY INVISIBLE (-7825 2475);
FORCEPROP 1 LAST TOLERANCE 1%
J 0
(-7775 2275);
DISPLAY 0.978723 (-7775 2275);
DISPLAY INVISIBLE (-7775 2275);
FORCEPROP 1 LAST WATTAGE 1/16W
J 2
(-7800 2225);
DISPLAY 0.978723 (-7800 2225);
DISPLAY INVISIBLE (-7800 2225);
FORCEPROP 1 LAST PACK_TYPE 0402LF
J 0
(-7525 2225);
DISPLAY 0.978723 (-7525 2225);
DISPLAY INVISIBLE (-7525 2225);
FORCEPROP 1 LAST MATERIAL CHIP
J 0
(-7775 2225);
DISPLAY 0.978723 (-7775 2225);
DISPLAY INVISIBLE (-7775 2225);
FORCEPROP 1 LAST PATH I242
J 0
(-7825 2525);
DISPLAY 0.978723 (-7825 2525);
PAINT WHITE (-7825 2525);
DISPLAY INVISIBLE (-7825 2525);
FORCEPROP 2 LAST CDS_LIB pure_quanta
J 0
(-7775 2375);
DISPLAY INVISIBLE (-7775 2375);
FORCEADD TAP..1
R 2
(-7725 2975);
FORCEPROP 3 LASTPIN (-7675 2975) SIG_NAME M_L_CPU0_SB_CB<2>
J 0
(-7665 2985);
DISPLAY 0.659574 (-7665 2985);
PAINT MONO (-7665 2985);
DISPLAY INVISIBLE (-7665 2985);
FORCEPROP 1 LASTPIN (-7675 2975) BN 2
J 2
(-7663 2983);
DISPLAY 0.489362 (-7663 2983);
PAINT GREEN (-7663 2983);
FORCEPROP 2 LAST CDS_LIB mstr_standard
J 0
(-7725 2975);
DISPLAY 0.723404 (-7725 2975);
PAINT MONO (-7725 2975);
DISPLAY INVISIBLE (-7725 2975);
FORCEPROP 1 LAST BODY_TYPE PLUMBING
J 2
(-7725 3025);
DISPLAY 0.872340 (-7725 3025);
PAINT GREEN (-7725 3025);
DISPLAY INVISIBLE (-7725 3025);
FORCEPROP 1 LAST HDL_TAP TRUE
J 2
(-8050 2850);
DISPLAY 0.872340 (-8050 2850);
DISPLAY INVISIBLE (-8050 2850);
FORCEPROP 1 LAST PATH I25
J 2
(-7723 2975);
DISPLAY 0.872340 (-7723 2975);
PAINT GREEN (-7723 2975);
DISPLAY INVISIBLE (-7723 2975);
FORCEADD TAP..1
R 2
(-7725 3075);
FORCEPROP 3 LASTPIN (-7675 3075) SIG_NAME M_L_CPU0_SB_CB<4>
J 0
(-7665 3085);
DISPLAY 0.659574 (-7665 3085);
PAINT MONO (-7665 3085);
DISPLAY INVISIBLE (-7665 3085);
FORCEPROP 1 LASTPIN (-7675 3075) BN 4
J 2
(-7663 3083);
DISPLAY 0.489362 (-7663 3083);
PAINT GREEN (-7663 3083);
FORCEPROP 2 LAST CDS_LIB mstr_standard
J 0
(-7725 3075);
DISPLAY 0.723404 (-7725 3075);
PAINT MONO (-7725 3075);
DISPLAY INVISIBLE (-7725 3075);
FORCEPROP 1 LAST BODY_TYPE PLUMBING
J 2
(-7725 3125);
DISPLAY 0.872340 (-7725 3125);
PAINT GREEN (-7725 3125);
DISPLAY INVISIBLE (-7725 3125);
FORCEPROP 1 LAST HDL_TAP TRUE
J 2
(-8050 2950);
DISPLAY 0.872340 (-8050 2950);
DISPLAY INVISIBLE (-8050 2950);
FORCEPROP 1 LAST PATH I26
J 2
(-7723 3075);
DISPLAY 0.872340 (-7723 3075);
PAINT GREEN (-7723 3075);
DISPLAY INVISIBLE (-7723 3075);
FORCEADD TAP..1
R 2
(-7725 3125);
FORCEPROP 3 LASTPIN (-7675 3125) SIG_NAME M_L_CPU0_SB_CB<5>
J 0
(-7665 3135);
DISPLAY 0.659574 (-7665 3135);
PAINT MONO (-7665 3135);
DISPLAY INVISIBLE (-7665 3135);
FORCEPROP 1 LASTPIN (-7675 3125) BN 5
J 2
(-7663 3133);
DISPLAY 0.489362 (-7663 3133);
PAINT GREEN (-7663 3133);
FORCEPROP 2 LAST CDS_LIB mstr_standard
J 0
(-7725 3125);
DISPLAY 0.723404 (-7725 3125);
PAINT MONO (-7725 3125);
DISPLAY INVISIBLE (-7725 3125);
FORCEPROP 1 LAST BODY_TYPE PLUMBING
J 2
(-7725 3175);
DISPLAY 0.872340 (-7725 3175);
PAINT GREEN (-7725 3175);
DISPLAY INVISIBLE (-7725 3175);
FORCEPROP 1 LAST HDL_TAP TRUE
J 2
(-8050 3000);
DISPLAY 0.872340 (-8050 3000);
DISPLAY INVISIBLE (-8050 3000);
FORCEPROP 1 LAST PATH I27
J 2
(-7723 3125);
DISPLAY 0.872340 (-7723 3125);
PAINT GREEN (-7723 3125);
DISPLAY INVISIBLE (-7723 3125);
FORCEADD TAP..1
R 2
(-7725 3025);
FORCEPROP 3 LASTPIN (-7675 3025) SIG_NAME M_L_CPU0_SB_CB<3>
J 0
(-7665 3035);
DISPLAY 0.659574 (-7665 3035);
PAINT MONO (-7665 3035);
DISPLAY INVISIBLE (-7665 3035);
FORCEPROP 1 LASTPIN (-7675 3025) BN 3
J 2
(-7663 3033);
DISPLAY 0.489362 (-7663 3033);
PAINT GREEN (-7663 3033);
FORCEPROP 2 LAST CDS_LIB mstr_standard
J 0
(-7725 3025);
DISPLAY 0.723404 (-7725 3025);
PAINT MONO (-7725 3025);
DISPLAY INVISIBLE (-7725 3025);
FORCEPROP 1 LAST BODY_TYPE PLUMBING
J 2
(-7725 3075);
DISPLAY 0.872340 (-7725 3075);
PAINT GREEN (-7725 3075);
DISPLAY INVISIBLE (-7725 3075);
FORCEPROP 1 LAST HDL_TAP TRUE
J 2
(-8050 2900);
DISPLAY 0.872340 (-8050 2900);
DISPLAY INVISIBLE (-8050 2900);
FORCEPROP 1 LAST PATH I28
J 2
(-7723 3025);
DISPLAY 0.872340 (-7723 3025);
PAINT GREEN (-7723 3025);
DISPLAY INVISIBLE (-7723 3025);
FORCEADD TAP..1
R 2
(-7725 3225);
FORCEPROP 3 LASTPIN (-7675 3225) SIG_NAME M_L_CPU0_SB_CB<7>
J 0
(-7665 3235);
DISPLAY 0.659574 (-7665 3235);
PAINT MONO (-7665 3235);
DISPLAY INVISIBLE (-7665 3235);
FORCEPROP 1 LASTPIN (-7675 3225) BN 7
J 2
(-7663 3233);
DISPLAY 0.489362 (-7663 3233);
PAINT GREEN (-7663 3233);
FORCEPROP 2 LAST CDS_LIB mstr_standard
J 0
(-7725 3225);
DISPLAY 0.723404 (-7725 3225);
PAINT MONO (-7725 3225);
DISPLAY INVISIBLE (-7725 3225);
FORCEPROP 1 LAST BODY_TYPE PLUMBING
J 2
(-7725 3275);
DISPLAY 0.872340 (-7725 3275);
PAINT GREEN (-7725 3275);
DISPLAY INVISIBLE (-7725 3275);
FORCEPROP 1 LAST HDL_TAP TRUE
J 2
(-8050 3100);
DISPLAY 0.872340 (-8050 3100);
DISPLAY INVISIBLE (-8050 3100);
FORCEPROP 1 LAST PATH I29
J 2
(-7723 3225);
DISPLAY 0.872340 (-7723 3225);
PAINT GREEN (-7723 3225);
DISPLAY INVISIBLE (-7723 3225);
FORCEADD TAP..1
R 2
(-7725 3375);
FORCEPROP 3 LASTPIN (-7675 3375) SIG_NAME M_L_CPU0_SA_CB<1>
J 0
(-7665 3385);
DISPLAY 0.659574 (-7665 3385);
PAINT MONO (-7665 3385);
DISPLAY INVISIBLE (-7665 3385);
FORCEPROP 1 LASTPIN (-7675 3375) BN 1
J 2
(-7663 3383);
DISPLAY 0.489362 (-7663 3383);
PAINT GREEN (-7663 3383);
FORCEPROP 2 LAST CDS_LIB mstr_standard
J 0
(-7725 3375);
DISPLAY 0.723404 (-7725 3375);
PAINT MONO (-7725 3375);
DISPLAY INVISIBLE (-7725 3375);
FORCEPROP 1 LAST BODY_TYPE PLUMBING
J 2
(-7725 3425);
DISPLAY 0.872340 (-7725 3425);
PAINT GREEN (-7725 3425);
DISPLAY INVISIBLE (-7725 3425);
FORCEPROP 1 LAST HDL_TAP TRUE
J 2
(-8050 3250);
DISPLAY 0.872340 (-8050 3250);
DISPLAY INVISIBLE (-8050 3250);
FORCEPROP 1 LAST PATH I30
J 2
(-7723 3375);
DISPLAY 0.872340 (-7723 3375);
PAINT GREEN (-7723 3375);
DISPLAY INVISIBLE (-7723 3375);
FORCEADD TAP..1
R 2
(-7725 3325);
FORCEPROP 3 LASTPIN (-7675 3325) SIG_NAME M_L_CPU0_SA_CB<0>
J 0
(-7665 3335);
DISPLAY 0.659574 (-7665 3335);
PAINT MONO (-7665 3335);
DISPLAY INVISIBLE (-7665 3335);
FORCEPROP 1 LASTPIN (-7675 3325) BN 0
J 2
(-7663 3333);
DISPLAY 0.489362 (-7663 3333);
PAINT GREEN (-7663 3333);
FORCEPROP 2 LAST CDS_LIB mstr_standard
J 0
(-7725 3325);
DISPLAY 0.723404 (-7725 3325);
PAINT MONO (-7725 3325);
DISPLAY INVISIBLE (-7725 3325);
FORCEPROP 1 LAST BODY_TYPE PLUMBING
J 2
(-7725 3375);
DISPLAY 0.872340 (-7725 3375);
PAINT GREEN (-7725 3375);
DISPLAY INVISIBLE (-7725 3375);
FORCEPROP 1 LAST HDL_TAP TRUE
J 2
(-8050 3200);
DISPLAY 0.872340 (-8050 3200);
DISPLAY INVISIBLE (-8050 3200);
FORCEPROP 1 LAST PATH I31
J 2
(-7723 3325);
DISPLAY 0.872340 (-7723 3325);
PAINT GREEN (-7723 3325);
DISPLAY INVISIBLE (-7723 3325);
FORCEADD TAP..1
R 2
(-7725 3175);
FORCEPROP 3 LASTPIN (-7675 3175) SIG_NAME M_L_CPU0_SB_CB<6>
J 0
(-7665 3185);
DISPLAY 0.659574 (-7665 3185);
PAINT MONO (-7665 3185);
DISPLAY INVISIBLE (-7665 3185);
FORCEPROP 1 LASTPIN (-7675 3175) BN 6
J 2
(-7663 3183);
DISPLAY 0.489362 (-7663 3183);
PAINT GREEN (-7663 3183);
FORCEPROP 2 LAST CDS_LIB mstr_standard
J 0
(-7725 3175);
DISPLAY 0.723404 (-7725 3175);
PAINT MONO (-7725 3175);
DISPLAY INVISIBLE (-7725 3175);
FORCEPROP 1 LAST BODY_TYPE PLUMBING
J 2
(-7725 3225);
DISPLAY 0.872340 (-7725 3225);
PAINT GREEN (-7725 3225);
DISPLAY INVISIBLE (-7725 3225);
FORCEPROP 1 LAST HDL_TAP TRUE
J 2
(-8050 3050);
DISPLAY 0.872340 (-8050 3050);
DISPLAY INVISIBLE (-8050 3050);
FORCEPROP 1 LAST PATH I32
J 2
(-7723 3175);
DISPLAY 0.872340 (-7723 3175);
PAINT GREEN (-7723 3175);
DISPLAY INVISIBLE (-7723 3175);
FORCEADD TAP..1
(-6025 1875);
FORCEPROP 3 LASTPIN (-6075 1875) SIG_NAME M_L_CPU0_SB_DQ<0>
J 0
(-6065 1885);
DISPLAY 0.659574 (-6065 1885);
PAINT MONO (-6065 1885);
DISPLAY INVISIBLE (-6065 1885);
FORCEPROP 1 LASTPIN (-6075 1875) BN 0
J 0
(-6087 1883);
DISPLAY 0.489362 (-6087 1883);
PAINT GREEN (-6087 1883);
FORCEPROP 2 LAST CDS_LIB mstr_standard
J 0
(-6025 1875);
DISPLAY 0.723404 (-6025 1875);
PAINT MONO (-6025 1875);
DISPLAY INVISIBLE (-6025 1875);
FORCEPROP 1 LAST BODY_TYPE PLUMBING
J 0
(-6025 1925);
DISPLAY 0.872340 (-6025 1925);
PAINT GREEN (-6025 1925);
DISPLAY INVISIBLE (-6025 1925);
FORCEPROP 1 LAST HDL_TAP TRUE
J 0
(-5700 1750);
DISPLAY 0.872340 (-5700 1750);
DISPLAY INVISIBLE (-5700 1750);
FORCEPROP 1 LAST PATH I33
J 0
(-6027 1875);
DISPLAY 0.872340 (-6027 1875);
PAINT GREEN (-6027 1875);
DISPLAY INVISIBLE (-6027 1875);
FORCEADD TAP..1
(-6025 1925);
FORCEPROP 3 LASTPIN (-6075 1925) SIG_NAME M_L_CPU0_SB_DQ<1>
J 0
(-6065 1935);
DISPLAY 0.659574 (-6065 1935);
PAINT MONO (-6065 1935);
DISPLAY INVISIBLE (-6065 1935);
FORCEPROP 1 LASTPIN (-6075 1925) BN 1
J 0
(-6087 1933);
DISPLAY 0.489362 (-6087 1933);
PAINT GREEN (-6087 1933);
FORCEPROP 2 LAST CDS_LIB mstr_standard
J 0
(-6025 1925);
DISPLAY 0.723404 (-6025 1925);
PAINT MONO (-6025 1925);
DISPLAY INVISIBLE (-6025 1925);
FORCEPROP 1 LAST BODY_TYPE PLUMBING
J 0
(-6025 1975);
DISPLAY 0.872340 (-6025 1975);
PAINT GREEN (-6025 1975);
DISPLAY INVISIBLE (-6025 1975);
FORCEPROP 1 LAST HDL_TAP TRUE
J 0
(-5700 1800);
DISPLAY 0.872340 (-5700 1800);
DISPLAY INVISIBLE (-5700 1800);
FORCEPROP 1 LAST PATH I34
J 0
(-6027 1925);
DISPLAY 0.872340 (-6027 1925);
PAINT GREEN (-6027 1925);
DISPLAY INVISIBLE (-6027 1925);
FORCEADD TAP..1
(-6025 1975);
FORCEPROP 3 LASTPIN (-6075 1975) SIG_NAME M_L_CPU0_SB_DQ<2>
J 0
(-6065 1985);
DISPLAY 0.659574 (-6065 1985);
PAINT MONO (-6065 1985);
DISPLAY INVISIBLE (-6065 1985);
FORCEPROP 1 LASTPIN (-6075 1975) BN 2
J 0
(-6087 1983);
DISPLAY 0.489362 (-6087 1983);
PAINT GREEN (-6087 1983);
FORCEPROP 2 LAST CDS_LIB mstr_standard
J 0
(-6025 1975);
DISPLAY 0.723404 (-6025 1975);
PAINT MONO (-6025 1975);
DISPLAY INVISIBLE (-6025 1975);
FORCEPROP 1 LAST BODY_TYPE PLUMBING
J 0
(-6025 2025);
DISPLAY 0.872340 (-6025 2025);
PAINT GREEN (-6025 2025);
DISPLAY INVISIBLE (-6025 2025);
FORCEPROP 1 LAST HDL_TAP TRUE
J 0
(-5700 1850);
DISPLAY 0.872340 (-5700 1850);
DISPLAY INVISIBLE (-5700 1850);
FORCEPROP 1 LAST PATH I35
J 0
(-6027 1975);
DISPLAY 0.872340 (-6027 1975);
PAINT GREEN (-6027 1975);
DISPLAY INVISIBLE (-6027 1975);
FORCEADD TAP..1
(-6025 2025);
FORCEPROP 3 LASTPIN (-6075 2025) SIG_NAME M_L_CPU0_SB_DQ<3>
J 0
(-6065 2035);
DISPLAY 0.659574 (-6065 2035);
PAINT MONO (-6065 2035);
DISPLAY INVISIBLE (-6065 2035);
FORCEPROP 1 LASTPIN (-6075 2025) BN 3
J 0
(-6087 2033);
DISPLAY 0.489362 (-6087 2033);
PAINT GREEN (-6087 2033);
FORCEPROP 2 LAST CDS_LIB mstr_standard
J 0
(-6025 2025);
DISPLAY 0.723404 (-6025 2025);
PAINT MONO (-6025 2025);
DISPLAY INVISIBLE (-6025 2025);
FORCEPROP 1 LAST BODY_TYPE PLUMBING
J 0
(-6025 2075);
DISPLAY 0.872340 (-6025 2075);
PAINT GREEN (-6025 2075);
DISPLAY INVISIBLE (-6025 2075);
FORCEPROP 1 LAST HDL_TAP TRUE
J 0
(-5700 1900);
DISPLAY 0.872340 (-5700 1900);
DISPLAY INVISIBLE (-5700 1900);
FORCEPROP 1 LAST PATH I36
J 0
(-6027 2025);
DISPLAY 0.872340 (-6027 2025);
PAINT GREEN (-6027 2025);
DISPLAY INVISIBLE (-6027 2025);
FORCEADD TAP..1
(-6025 2075);
FORCEPROP 3 LASTPIN (-6075 2075) SIG_NAME M_L_CPU0_SB_DQ<4>
J 0
(-6065 2085);
DISPLAY 0.659574 (-6065 2085);
PAINT MONO (-6065 2085);
DISPLAY INVISIBLE (-6065 2085);
FORCEPROP 1 LASTPIN (-6075 2075) BN 4
J 0
(-6087 2083);
DISPLAY 0.489362 (-6087 2083);
PAINT GREEN (-6087 2083);
FORCEPROP 2 LAST CDS_LIB mstr_standard
J 0
(-6025 2075);
DISPLAY 0.723404 (-6025 2075);
PAINT MONO (-6025 2075);
DISPLAY INVISIBLE (-6025 2075);
FORCEPROP 1 LAST BODY_TYPE PLUMBING
J 0
(-6025 2125);
DISPLAY 0.872340 (-6025 2125);
PAINT GREEN (-6025 2125);
DISPLAY INVISIBLE (-6025 2125);
FORCEPROP 1 LAST HDL_TAP TRUE
J 0
(-5700 1950);
DISPLAY 0.872340 (-5700 1950);
DISPLAY INVISIBLE (-5700 1950);
FORCEPROP 1 LAST PATH I37
J 0
(-6027 2075);
DISPLAY 0.872340 (-6027 2075);
PAINT GREEN (-6027 2075);
DISPLAY INVISIBLE (-6027 2075);
FORCEADD TAP..1
(-6025 2125);
FORCEPROP 3 LASTPIN (-6075 2125) SIG_NAME M_L_CPU0_SB_DQ<5>
J 0
(-6065 2135);
DISPLAY 0.659574 (-6065 2135);
PAINT MONO (-6065 2135);
DISPLAY INVISIBLE (-6065 2135);
FORCEPROP 1 LASTPIN (-6075 2125) BN 5
J 0
(-6087 2133);
DISPLAY 0.489362 (-6087 2133);
PAINT GREEN (-6087 2133);
FORCEPROP 2 LAST CDS_LIB mstr_standard
J 0
(-6025 2125);
DISPLAY 0.723404 (-6025 2125);
PAINT MONO (-6025 2125);
DISPLAY INVISIBLE (-6025 2125);
FORCEPROP 1 LAST BODY_TYPE PLUMBING
J 0
(-6025 2175);
DISPLAY 0.872340 (-6025 2175);
PAINT GREEN (-6025 2175);
DISPLAY INVISIBLE (-6025 2175);
FORCEPROP 1 LAST HDL_TAP TRUE
J 0
(-5700 2000);
DISPLAY 0.872340 (-5700 2000);
DISPLAY INVISIBLE (-5700 2000);
FORCEPROP 1 LAST PATH I38
J 0
(-6027 2125);
DISPLAY 0.872340 (-6027 2125);
PAINT GREEN (-6027 2125);
DISPLAY INVISIBLE (-6027 2125);
FORCEADD TAP..1
(-6025 2175);
FORCEPROP 3 LASTPIN (-6075 2175) SIG_NAME M_L_CPU0_SB_DQ<6>
J 0
(-6065 2185);
DISPLAY 0.659574 (-6065 2185);
PAINT MONO (-6065 2185);
DISPLAY INVISIBLE (-6065 2185);
FORCEPROP 1 LASTPIN (-6075 2175) BN 6
J 0
(-6087 2183);
DISPLAY 0.489362 (-6087 2183);
PAINT GREEN (-6087 2183);
FORCEPROP 2 LAST CDS_LIB mstr_standard
J 0
(-6025 2175);
DISPLAY 0.723404 (-6025 2175);
PAINT MONO (-6025 2175);
DISPLAY INVISIBLE (-6025 2175);
FORCEPROP 1 LAST BODY_TYPE PLUMBING
J 0
(-6025 2225);
DISPLAY 0.872340 (-6025 2225);
PAINT GREEN (-6025 2225);
DISPLAY INVISIBLE (-6025 2225);
FORCEPROP 1 LAST HDL_TAP TRUE
J 0
(-5700 2050);
DISPLAY 0.872340 (-5700 2050);
DISPLAY INVISIBLE (-5700 2050);
FORCEPROP 1 LAST PATH I39
J 0
(-6027 2175);
DISPLAY 0.872340 (-6027 2175);
PAINT GREEN (-6027 2175);
DISPLAY INVISIBLE (-6027 2175);
FORCEADD TAP..1
(-6025 2225);
FORCEPROP 3 LASTPIN (-6075 2225) SIG_NAME M_L_CPU0_SB_DQ<7>
J 0
(-6065 2235);
DISPLAY 0.659574 (-6065 2235);
PAINT MONO (-6065 2235);
DISPLAY INVISIBLE (-6065 2235);
FORCEPROP 1 LASTPIN (-6075 2225) BN 7
J 0
(-6087 2233);
DISPLAY 0.489362 (-6087 2233);
PAINT GREEN (-6087 2233);
FORCEPROP 2 LAST CDS_LIB mstr_standard
J 0
(-6025 2225);
DISPLAY 0.723404 (-6025 2225);
PAINT MONO (-6025 2225);
DISPLAY INVISIBLE (-6025 2225);
FORCEPROP 1 LAST BODY_TYPE PLUMBING
J 0
(-6025 2275);
DISPLAY 0.872340 (-6025 2275);
PAINT GREEN (-6025 2275);
DISPLAY INVISIBLE (-6025 2275);
FORCEPROP 1 LAST HDL_TAP TRUE
J 0
(-5700 2100);
DISPLAY 0.872340 (-5700 2100);
DISPLAY INVISIBLE (-5700 2100);
FORCEPROP 1 LAST PATH I40
J 0
(-6027 2225);
DISPLAY 0.872340 (-6027 2225);
PAINT GREEN (-6027 2225);
DISPLAY INVISIBLE (-6027 2225);
FORCEADD TAP..1
(-6025 2275);
FORCEPROP 3 LASTPIN (-6075 2275) SIG_NAME M_L_CPU0_SB_DQ<8>
J 0
(-6065 2285);
DISPLAY 0.659574 (-6065 2285);
PAINT MONO (-6065 2285);
DISPLAY INVISIBLE (-6065 2285);
FORCEPROP 1 LASTPIN (-6075 2275) BN 8
J 0
(-6087 2283);
DISPLAY 0.489362 (-6087 2283);
PAINT GREEN (-6087 2283);
FORCEPROP 2 LAST CDS_LIB mstr_standard
J 0
(-6025 2275);
DISPLAY 0.723404 (-6025 2275);
PAINT MONO (-6025 2275);
DISPLAY INVISIBLE (-6025 2275);
FORCEPROP 1 LAST BODY_TYPE PLUMBING
J 0
(-6025 2325);
DISPLAY 0.872340 (-6025 2325);
PAINT GREEN (-6025 2325);
DISPLAY INVISIBLE (-6025 2325);
FORCEPROP 1 LAST HDL_TAP TRUE
J 0
(-5700 2150);
DISPLAY 0.872340 (-5700 2150);
DISPLAY INVISIBLE (-5700 2150);
FORCEPROP 1 LAST PATH I41
J 0
(-6027 2275);
DISPLAY 0.872340 (-6027 2275);
PAINT GREEN (-6027 2275);
DISPLAY INVISIBLE (-6027 2275);
FORCEADD TAP..1
(-6025 2375);
FORCEPROP 3 LASTPIN (-6075 2375) SIG_NAME M_L_CPU0_SB_DQ<10>
J 0
(-6065 2385);
DISPLAY 0.659574 (-6065 2385);
PAINT MONO (-6065 2385);
DISPLAY INVISIBLE (-6065 2385);
FORCEPROP 1 LASTPIN (-6075 2375) BN 10
J 0
(-6087 2383);
DISPLAY 0.489362 (-6087 2383);
PAINT GREEN (-6087 2383);
FORCEPROP 2 LAST CDS_LIB mstr_standard
J 0
(-6025 2375);
DISPLAY 0.723404 (-6025 2375);
PAINT MONO (-6025 2375);
DISPLAY INVISIBLE (-6025 2375);
FORCEPROP 1 LAST BODY_TYPE PLUMBING
J 0
(-6025 2425);
DISPLAY 0.872340 (-6025 2425);
PAINT GREEN (-6025 2425);
DISPLAY INVISIBLE (-6025 2425);
FORCEPROP 1 LAST HDL_TAP TRUE
J 0
(-5700 2250);
DISPLAY 0.872340 (-5700 2250);
DISPLAY INVISIBLE (-5700 2250);
FORCEPROP 1 LAST PATH I42
J 0
(-6027 2375);
DISPLAY 0.872340 (-6027 2375);
PAINT GREEN (-6027 2375);
DISPLAY INVISIBLE (-6027 2375);
FORCEADD TAP..1
(-6025 2325);
FORCEPROP 3 LASTPIN (-6075 2325) SIG_NAME M_L_CPU0_SB_DQ<9>
J 0
(-6065 2335);
DISPLAY 0.659574 (-6065 2335);
PAINT MONO (-6065 2335);
DISPLAY INVISIBLE (-6065 2335);
FORCEPROP 1 LASTPIN (-6075 2325) BN 9
J 0
(-6087 2333);
DISPLAY 0.489362 (-6087 2333);
PAINT GREEN (-6087 2333);
FORCEPROP 2 LAST CDS_LIB mstr_standard
J 0
(-6025 2325);
DISPLAY 0.723404 (-6025 2325);
PAINT MONO (-6025 2325);
DISPLAY INVISIBLE (-6025 2325);
FORCEPROP 1 LAST BODY_TYPE PLUMBING
J 0
(-6025 2375);
DISPLAY 0.872340 (-6025 2375);
PAINT GREEN (-6025 2375);
DISPLAY INVISIBLE (-6025 2375);
FORCEPROP 1 LAST HDL_TAP TRUE
J 0
(-5700 2200);
DISPLAY 0.872340 (-5700 2200);
DISPLAY INVISIBLE (-5700 2200);
FORCEPROP 1 LAST PATH I43
J 0
(-6027 2325);
DISPLAY 0.872340 (-6027 2325);
PAINT GREEN (-6027 2325);
DISPLAY INVISIBLE (-6027 2325);
FORCEADD TAP..1
(-6025 2425);
FORCEPROP 3 LASTPIN (-6075 2425) SIG_NAME M_L_CPU0_SB_DQ<11>
J 0
(-6065 2435);
DISPLAY 0.659574 (-6065 2435);
PAINT MONO (-6065 2435);
DISPLAY INVISIBLE (-6065 2435);
FORCEPROP 1 LASTPIN (-6075 2425) BN 11
J 0
(-6087 2433);
DISPLAY 0.489362 (-6087 2433);
PAINT GREEN (-6087 2433);
FORCEPROP 2 LAST CDS_LIB mstr_standard
J 0
(-6025 2425);
DISPLAY 0.723404 (-6025 2425);
PAINT MONO (-6025 2425);
DISPLAY INVISIBLE (-6025 2425);
FORCEPROP 1 LAST BODY_TYPE PLUMBING
J 0
(-6025 2475);
DISPLAY 0.872340 (-6025 2475);
PAINT GREEN (-6025 2475);
DISPLAY INVISIBLE (-6025 2475);
FORCEPROP 1 LAST HDL_TAP TRUE
J 0
(-5700 2300);
DISPLAY 0.872340 (-5700 2300);
DISPLAY INVISIBLE (-5700 2300);
FORCEPROP 1 LAST PATH I44
J 0
(-6027 2425);
DISPLAY 0.872340 (-6027 2425);
PAINT GREEN (-6027 2425);
DISPLAY INVISIBLE (-6027 2425);
FORCEADD TAP..1
(-6025 2475);
FORCEPROP 3 LASTPIN (-6075 2475) SIG_NAME M_L_CPU0_SB_DQ<12>
J 0
(-6065 2485);
DISPLAY 0.659574 (-6065 2485);
PAINT MONO (-6065 2485);
DISPLAY INVISIBLE (-6065 2485);
FORCEPROP 1 LASTPIN (-6075 2475) BN 12
J 0
(-6087 2483);
DISPLAY 0.489362 (-6087 2483);
PAINT GREEN (-6087 2483);
FORCEPROP 2 LAST CDS_LIB mstr_standard
J 0
(-6025 2475);
DISPLAY 0.723404 (-6025 2475);
PAINT MONO (-6025 2475);
DISPLAY INVISIBLE (-6025 2475);
FORCEPROP 1 LAST BODY_TYPE PLUMBING
J 0
(-6025 2525);
DISPLAY 0.872340 (-6025 2525);
PAINT GREEN (-6025 2525);
DISPLAY INVISIBLE (-6025 2525);
FORCEPROP 1 LAST HDL_TAP TRUE
J 0
(-5700 2350);
DISPLAY 0.872340 (-5700 2350);
DISPLAY INVISIBLE (-5700 2350);
FORCEPROP 1 LAST PATH I45
J 0
(-6027 2475);
DISPLAY 0.872340 (-6027 2475);
PAINT GREEN (-6027 2475);
DISPLAY INVISIBLE (-6027 2475);
FORCEADD TAP..1
(-6025 2525);
FORCEPROP 3 LASTPIN (-6075 2525) SIG_NAME M_L_CPU0_SB_DQ<13>
J 0
(-6065 2535);
DISPLAY 0.659574 (-6065 2535);
PAINT MONO (-6065 2535);
DISPLAY INVISIBLE (-6065 2535);
FORCEPROP 1 LASTPIN (-6075 2525) BN 13
J 0
(-6087 2533);
DISPLAY 0.489362 (-6087 2533);
PAINT GREEN (-6087 2533);
FORCEPROP 2 LAST CDS_LIB mstr_standard
J 0
(-6025 2525);
DISPLAY 0.723404 (-6025 2525);
PAINT MONO (-6025 2525);
DISPLAY INVISIBLE (-6025 2525);
FORCEPROP 1 LAST BODY_TYPE PLUMBING
J 0
(-6025 2575);
DISPLAY 0.872340 (-6025 2575);
PAINT GREEN (-6025 2575);
DISPLAY INVISIBLE (-6025 2575);
FORCEPROP 1 LAST HDL_TAP TRUE
J 0
(-5700 2400);
DISPLAY 0.872340 (-5700 2400);
DISPLAY INVISIBLE (-5700 2400);
FORCEPROP 1 LAST PATH I46
J 0
(-6027 2525);
DISPLAY 0.872340 (-6027 2525);
PAINT GREEN (-6027 2525);
DISPLAY INVISIBLE (-6027 2525);
FORCEADD TAP..1
(-6025 2575);
FORCEPROP 3 LASTPIN (-6075 2575) SIG_NAME M_L_CPU0_SB_DQ<14>
J 0
(-6065 2585);
DISPLAY 0.659574 (-6065 2585);
PAINT MONO (-6065 2585);
DISPLAY INVISIBLE (-6065 2585);
FORCEPROP 1 LASTPIN (-6075 2575) BN 14
J 0
(-6087 2583);
DISPLAY 0.489362 (-6087 2583);
PAINT GREEN (-6087 2583);
FORCEPROP 2 LAST CDS_LIB mstr_standard
J 0
(-6025 2575);
DISPLAY 0.723404 (-6025 2575);
PAINT MONO (-6025 2575);
DISPLAY INVISIBLE (-6025 2575);
FORCEPROP 1 LAST BODY_TYPE PLUMBING
J 0
(-6025 2625);
DISPLAY 0.872340 (-6025 2625);
PAINT GREEN (-6025 2625);
DISPLAY INVISIBLE (-6025 2625);
FORCEPROP 1 LAST HDL_TAP TRUE
J 0
(-5700 2450);
DISPLAY 0.872340 (-5700 2450);
DISPLAY INVISIBLE (-5700 2450);
FORCEPROP 1 LAST PATH I47
J 0
(-6027 2575);
DISPLAY 0.872340 (-6027 2575);
PAINT GREEN (-6027 2575);
DISPLAY INVISIBLE (-6027 2575);
FORCEADD TAP..1
(-6025 2625);
FORCEPROP 3 LASTPIN (-6075 2625) SIG_NAME M_L_CPU0_SB_DQ<15>
J 0
(-6065 2635);
DISPLAY 0.659574 (-6065 2635);
PAINT MONO (-6065 2635);
DISPLAY INVISIBLE (-6065 2635);
FORCEPROP 1 LASTPIN (-6075 2625) BN 15
J 0
(-6087 2633);
DISPLAY 0.489362 (-6087 2633);
PAINT GREEN (-6087 2633);
FORCEPROP 2 LAST CDS_LIB mstr_standard
J 0
(-6025 2625);
DISPLAY 0.723404 (-6025 2625);
PAINT MONO (-6025 2625);
DISPLAY INVISIBLE (-6025 2625);
FORCEPROP 1 LAST BODY_TYPE PLUMBING
J 0
(-6025 2675);
DISPLAY 0.872340 (-6025 2675);
PAINT GREEN (-6025 2675);
DISPLAY INVISIBLE (-6025 2675);
FORCEPROP 1 LAST HDL_TAP TRUE
J 0
(-5700 2500);
DISPLAY 0.872340 (-5700 2500);
DISPLAY INVISIBLE (-5700 2500);
FORCEPROP 1 LAST PATH I48
J 0
(-6027 2625);
DISPLAY 0.872340 (-6027 2625);
PAINT GREEN (-6027 2625);
DISPLAY INVISIBLE (-6027 2625);
FORCEADD TAP..1
(-6025 2675);
FORCEPROP 3 LASTPIN (-6075 2675) SIG_NAME M_L_CPU0_SB_DQ<16>
J 0
(-6065 2685);
DISPLAY 0.659574 (-6065 2685);
PAINT MONO (-6065 2685);
DISPLAY INVISIBLE (-6065 2685);
FORCEPROP 1 LASTPIN (-6075 2675) BN 16
J 0
(-6087 2683);
DISPLAY 0.489362 (-6087 2683);
PAINT GREEN (-6087 2683);
FORCEPROP 2 LAST CDS_LIB mstr_standard
J 0
(-6025 2675);
DISPLAY 0.723404 (-6025 2675);
PAINT MONO (-6025 2675);
DISPLAY INVISIBLE (-6025 2675);
FORCEPROP 1 LAST BODY_TYPE PLUMBING
J 0
(-6025 2725);
DISPLAY 0.872340 (-6025 2725);
PAINT GREEN (-6025 2725);
DISPLAY INVISIBLE (-6025 2725);
FORCEPROP 1 LAST HDL_TAP TRUE
J 0
(-5700 2550);
DISPLAY 0.872340 (-5700 2550);
DISPLAY INVISIBLE (-5700 2550);
FORCEPROP 1 LAST PATH I49
J 0
(-6027 2675);
DISPLAY 0.872340 (-6027 2675);
PAINT GREEN (-6027 2675);
DISPLAY INVISIBLE (-6027 2675);
FORCEADD TAP..1
(-6025 2725);
FORCEPROP 3 LASTPIN (-6075 2725) SIG_NAME M_L_CPU0_SB_DQ<17>
J 0
(-6065 2735);
DISPLAY 0.659574 (-6065 2735);
PAINT MONO (-6065 2735);
DISPLAY INVISIBLE (-6065 2735);
FORCEPROP 1 LASTPIN (-6075 2725) BN 17
J 0
(-6087 2733);
DISPLAY 0.489362 (-6087 2733);
PAINT GREEN (-6087 2733);
FORCEPROP 2 LAST CDS_LIB mstr_standard
J 0
(-6025 2725);
DISPLAY 0.723404 (-6025 2725);
PAINT MONO (-6025 2725);
DISPLAY INVISIBLE (-6025 2725);
FORCEPROP 1 LAST BODY_TYPE PLUMBING
J 0
(-6025 2775);
DISPLAY 0.872340 (-6025 2775);
PAINT GREEN (-6025 2775);
DISPLAY INVISIBLE (-6025 2775);
FORCEPROP 1 LAST HDL_TAP TRUE
J 0
(-5700 2600);
DISPLAY 0.872340 (-5700 2600);
DISPLAY INVISIBLE (-5700 2600);
FORCEPROP 1 LAST PATH I50
J 0
(-6027 2725);
DISPLAY 0.872340 (-6027 2725);
PAINT GREEN (-6027 2725);
DISPLAY INVISIBLE (-6027 2725);
FORCEADD TAP..1
(-6025 2775);
FORCEPROP 3 LASTPIN (-6075 2775) SIG_NAME M_L_CPU0_SB_DQ<18>
J 0
(-6065 2785);
DISPLAY 0.659574 (-6065 2785);
PAINT MONO (-6065 2785);
DISPLAY INVISIBLE (-6065 2785);
FORCEPROP 1 LASTPIN (-6075 2775) BN 18
J 0
(-6087 2783);
DISPLAY 0.489362 (-6087 2783);
PAINT GREEN (-6087 2783);
FORCEPROP 2 LAST CDS_LIB mstr_standard
J 0
(-6025 2775);
DISPLAY 0.723404 (-6025 2775);
PAINT MONO (-6025 2775);
DISPLAY INVISIBLE (-6025 2775);
FORCEPROP 1 LAST BODY_TYPE PLUMBING
J 0
(-6025 2825);
DISPLAY 0.872340 (-6025 2825);
PAINT GREEN (-6025 2825);
DISPLAY INVISIBLE (-6025 2825);
FORCEPROP 1 LAST HDL_TAP TRUE
J 0
(-5700 2650);
DISPLAY 0.872340 (-5700 2650);
DISPLAY INVISIBLE (-5700 2650);
FORCEPROP 1 LAST PATH I51
J 0
(-6027 2775);
DISPLAY 0.872340 (-6027 2775);
PAINT GREEN (-6027 2775);
DISPLAY INVISIBLE (-6027 2775);
FORCEADD TAP..1
(-6025 2825);
FORCEPROP 3 LASTPIN (-6075 2825) SIG_NAME M_L_CPU0_SB_DQ<19>
J 0
(-6065 2835);
DISPLAY 0.659574 (-6065 2835);
PAINT MONO (-6065 2835);
DISPLAY INVISIBLE (-6065 2835);
FORCEPROP 1 LASTPIN (-6075 2825) BN 19
J 0
(-6087 2833);
DISPLAY 0.489362 (-6087 2833);
PAINT GREEN (-6087 2833);
FORCEPROP 2 LAST CDS_LIB mstr_standard
J 0
(-6025 2825);
DISPLAY 0.723404 (-6025 2825);
PAINT MONO (-6025 2825);
DISPLAY INVISIBLE (-6025 2825);
FORCEPROP 1 LAST BODY_TYPE PLUMBING
J 0
(-6025 2875);
DISPLAY 0.872340 (-6025 2875);
PAINT GREEN (-6025 2875);
DISPLAY INVISIBLE (-6025 2875);
FORCEPROP 1 LAST HDL_TAP TRUE
J 0
(-5700 2700);
DISPLAY 0.872340 (-5700 2700);
DISPLAY INVISIBLE (-5700 2700);
FORCEPROP 1 LAST PATH I52
J 0
(-6027 2825);
DISPLAY 0.872340 (-6027 2825);
PAINT GREEN (-6027 2825);
DISPLAY INVISIBLE (-6027 2825);
FORCEADD TAP..1
(-6025 2875);
FORCEPROP 3 LASTPIN (-6075 2875) SIG_NAME M_L_CPU0_SB_DQ<20>
J 0
(-6065 2885);
DISPLAY 0.659574 (-6065 2885);
PAINT MONO (-6065 2885);
DISPLAY INVISIBLE (-6065 2885);
FORCEPROP 1 LASTPIN (-6075 2875) BN 20
J 0
(-6087 2883);
DISPLAY 0.489362 (-6087 2883);
PAINT GREEN (-6087 2883);
FORCEPROP 2 LAST CDS_LIB mstr_standard
J 0
(-6025 2875);
DISPLAY 0.723404 (-6025 2875);
PAINT MONO (-6025 2875);
DISPLAY INVISIBLE (-6025 2875);
FORCEPROP 1 LAST BODY_TYPE PLUMBING
J 0
(-6025 2925);
DISPLAY 0.872340 (-6025 2925);
PAINT GREEN (-6025 2925);
DISPLAY INVISIBLE (-6025 2925);
FORCEPROP 1 LAST HDL_TAP TRUE
J 0
(-5700 2750);
DISPLAY 0.872340 (-5700 2750);
DISPLAY INVISIBLE (-5700 2750);
FORCEPROP 1 LAST PATH I53
J 0
(-6027 2875);
DISPLAY 0.872340 (-6027 2875);
PAINT GREEN (-6027 2875);
DISPLAY INVISIBLE (-6027 2875);
FORCEADD TAP..1
(-6025 2925);
FORCEPROP 3 LASTPIN (-6075 2925) SIG_NAME M_L_CPU0_SB_DQ<21>
J 0
(-6065 2935);
DISPLAY 0.659574 (-6065 2935);
PAINT MONO (-6065 2935);
DISPLAY INVISIBLE (-6065 2935);
FORCEPROP 1 LASTPIN (-6075 2925) BN 21
J 0
(-6087 2933);
DISPLAY 0.489362 (-6087 2933);
PAINT GREEN (-6087 2933);
FORCEPROP 2 LAST CDS_LIB mstr_standard
J 0
(-6025 2925);
DISPLAY 0.723404 (-6025 2925);
PAINT MONO (-6025 2925);
DISPLAY INVISIBLE (-6025 2925);
FORCEPROP 1 LAST BODY_TYPE PLUMBING
J 0
(-6025 2975);
DISPLAY 0.872340 (-6025 2975);
PAINT GREEN (-6025 2975);
DISPLAY INVISIBLE (-6025 2975);
FORCEPROP 1 LAST HDL_TAP TRUE
J 0
(-5700 2800);
DISPLAY 0.872340 (-5700 2800);
DISPLAY INVISIBLE (-5700 2800);
FORCEPROP 1 LAST PATH I54
J 0
(-6027 2925);
DISPLAY 0.872340 (-6027 2925);
PAINT GREEN (-6027 2925);
DISPLAY INVISIBLE (-6027 2925);
FORCEADD TAP..1
(-6025 2975);
FORCEPROP 3 LASTPIN (-6075 2975) SIG_NAME M_L_CPU0_SB_DQ<22>
J 0
(-6065 2985);
DISPLAY 0.659574 (-6065 2985);
PAINT MONO (-6065 2985);
DISPLAY INVISIBLE (-6065 2985);
FORCEPROP 1 LASTPIN (-6075 2975) BN 22
J 0
(-6087 2983);
DISPLAY 0.489362 (-6087 2983);
PAINT GREEN (-6087 2983);
FORCEPROP 2 LAST CDS_LIB mstr_standard
J 0
(-6025 2975);
DISPLAY 0.723404 (-6025 2975);
PAINT MONO (-6025 2975);
DISPLAY INVISIBLE (-6025 2975);
FORCEPROP 1 LAST BODY_TYPE PLUMBING
J 0
(-6025 3025);
DISPLAY 0.872340 (-6025 3025);
PAINT GREEN (-6025 3025);
DISPLAY INVISIBLE (-6025 3025);
FORCEPROP 1 LAST HDL_TAP TRUE
J 0
(-5700 2850);
DISPLAY 0.872340 (-5700 2850);
DISPLAY INVISIBLE (-5700 2850);
FORCEPROP 1 LAST PATH I55
J 0
(-6027 2975);
DISPLAY 0.872340 (-6027 2975);
PAINT GREEN (-6027 2975);
DISPLAY INVISIBLE (-6027 2975);
FORCEADD TAP..1
(-6025 3025);
FORCEPROP 3 LASTPIN (-6075 3025) SIG_NAME M_L_CPU0_SB_DQ<23>
J 0
(-6065 3035);
DISPLAY 0.659574 (-6065 3035);
PAINT MONO (-6065 3035);
DISPLAY INVISIBLE (-6065 3035);
FORCEPROP 1 LASTPIN (-6075 3025) BN 23
J 0
(-6087 3033);
DISPLAY 0.489362 (-6087 3033);
PAINT GREEN (-6087 3033);
FORCEPROP 2 LAST CDS_LIB mstr_standard
J 0
(-6025 3025);
DISPLAY 0.723404 (-6025 3025);
PAINT MONO (-6025 3025);
DISPLAY INVISIBLE (-6025 3025);
FORCEPROP 1 LAST BODY_TYPE PLUMBING
J 0
(-6025 3075);
DISPLAY 0.872340 (-6025 3075);
PAINT GREEN (-6025 3075);
DISPLAY INVISIBLE (-6025 3075);
FORCEPROP 1 LAST HDL_TAP TRUE
J 0
(-5700 2900);
DISPLAY 0.872340 (-5700 2900);
DISPLAY INVISIBLE (-5700 2900);
FORCEPROP 1 LAST PATH I56
J 0
(-6027 3025);
DISPLAY 0.872340 (-6027 3025);
PAINT GREEN (-6027 3025);
DISPLAY INVISIBLE (-6027 3025);
FORCEADD TAP..1
(-6025 3075);
FORCEPROP 3 LASTPIN (-6075 3075) SIG_NAME M_L_CPU0_SB_DQ<24>
J 0
(-6065 3085);
DISPLAY 0.659574 (-6065 3085);
PAINT MONO (-6065 3085);
DISPLAY INVISIBLE (-6065 3085);
FORCEPROP 1 LASTPIN (-6075 3075) BN 24
J 0
(-6087 3083);
DISPLAY 0.489362 (-6087 3083);
PAINT GREEN (-6087 3083);
FORCEPROP 2 LAST CDS_LIB mstr_standard
J 0
(-6025 3075);
DISPLAY 0.723404 (-6025 3075);
PAINT MONO (-6025 3075);
DISPLAY INVISIBLE (-6025 3075);
FORCEPROP 1 LAST BODY_TYPE PLUMBING
J 0
(-6025 3125);
DISPLAY 0.872340 (-6025 3125);
PAINT GREEN (-6025 3125);
DISPLAY INVISIBLE (-6025 3125);
FORCEPROP 1 LAST HDL_TAP TRUE
J 0
(-5700 2950);
DISPLAY 0.872340 (-5700 2950);
DISPLAY INVISIBLE (-5700 2950);
FORCEPROP 1 LAST PATH I57
J 0
(-6027 3075);
DISPLAY 0.872340 (-6027 3075);
PAINT GREEN (-6027 3075);
DISPLAY INVISIBLE (-6027 3075);
FORCEADD TAP..1
(-6025 3125);
FORCEPROP 3 LASTPIN (-6075 3125) SIG_NAME M_L_CPU0_SB_DQ<25>
J 0
(-6065 3135);
DISPLAY 0.659574 (-6065 3135);
PAINT MONO (-6065 3135);
DISPLAY INVISIBLE (-6065 3135);
FORCEPROP 1 LASTPIN (-6075 3125) BN 25
J 0
(-6087 3133);
DISPLAY 0.489362 (-6087 3133);
PAINT GREEN (-6087 3133);
FORCEPROP 2 LAST CDS_LIB mstr_standard
J 0
(-6025 3125);
DISPLAY 0.723404 (-6025 3125);
PAINT MONO (-6025 3125);
DISPLAY INVISIBLE (-6025 3125);
FORCEPROP 1 LAST BODY_TYPE PLUMBING
J 0
(-6025 3175);
DISPLAY 0.872340 (-6025 3175);
PAINT GREEN (-6025 3175);
DISPLAY INVISIBLE (-6025 3175);
FORCEPROP 1 LAST HDL_TAP TRUE
J 0
(-5700 3000);
DISPLAY 0.872340 (-5700 3000);
DISPLAY INVISIBLE (-5700 3000);
FORCEPROP 1 LAST PATH I58
J 0
(-6027 3125);
DISPLAY 0.872340 (-6027 3125);
PAINT GREEN (-6027 3125);
DISPLAY INVISIBLE (-6027 3125);
FORCEADD TAP..1
(-6025 3175);
FORCEPROP 3 LASTPIN (-6075 3175) SIG_NAME M_L_CPU0_SB_DQ<26>
J 0
(-6065 3185);
DISPLAY 0.659574 (-6065 3185);
PAINT MONO (-6065 3185);
DISPLAY INVISIBLE (-6065 3185);
FORCEPROP 1 LASTPIN (-6075 3175) BN 26
J 0
(-6087 3183);
DISPLAY 0.489362 (-6087 3183);
PAINT GREEN (-6087 3183);
FORCEPROP 2 LAST CDS_LIB mstr_standard
J 0
(-6025 3175);
DISPLAY 0.723404 (-6025 3175);
PAINT MONO (-6025 3175);
DISPLAY INVISIBLE (-6025 3175);
FORCEPROP 1 LAST BODY_TYPE PLUMBING
J 0
(-6025 3225);
DISPLAY 0.872340 (-6025 3225);
PAINT GREEN (-6025 3225);
DISPLAY INVISIBLE (-6025 3225);
FORCEPROP 1 LAST HDL_TAP TRUE
J 0
(-5700 3050);
DISPLAY 0.872340 (-5700 3050);
DISPLAY INVISIBLE (-5700 3050);
FORCEPROP 1 LAST PATH I59
J 0
(-6027 3175);
DISPLAY 0.872340 (-6027 3175);
PAINT GREEN (-6027 3175);
DISPLAY INVISIBLE (-6027 3175);
FORCEADD OFFPAGE..1
(-8325 2575);
FORCEPROP 2 LAST $XR0 96 
J 0
(-8546 2575);
DISPLAY 0.638298 (-8546 2575);
PAINT MONO (-8546 2575);
FORCEPROP 2 LAST CDS_LIB mstr_standard
J 0
(-8325 2575);
DISPLAY 0.808511 (-8325 2575);
DISPLAY INVISIBLE (-8325 2575);
FORCEPROP 1 LAST OFFPAGE TRUE
J 0
(-8000 2450);
DISPLAY 0.872340 (-8000 2450);
PAINT GREEN (-8000 2450);
DISPLAY INVISIBLE (-8000 2450);
FORCEPROP 1 LAST COMMENT_BODY TRUE
J 0
(-8200 2475);
DISPLAY 0.872340 (-8200 2475);
PAINT GREEN (-8200 2475);
DISPLAY INVISIBLE (-8200 2475);
FORCEPROP 2 LAST PATH I6
J 0
(-8575 2625);
DISPLAY 1.021277 (-8575 2625);
DISPLAY INVISIBLE (-8575 2625);
FORCEADD TAP..1
(-6025 3225);
FORCEPROP 3 LASTPIN (-6075 3225) SIG_NAME M_L_CPU0_SB_DQ<27>
J 0
(-6065 3235);
DISPLAY 0.659574 (-6065 3235);
PAINT MONO (-6065 3235);
DISPLAY INVISIBLE (-6065 3235);
FORCEPROP 1 LASTPIN (-6075 3225) BN 27
J 0
(-6087 3233);
DISPLAY 0.489362 (-6087 3233);
PAINT GREEN (-6087 3233);
FORCEPROP 2 LAST CDS_LIB mstr_standard
J 0
(-6025 3225);
DISPLAY 0.723404 (-6025 3225);
PAINT MONO (-6025 3225);
DISPLAY INVISIBLE (-6025 3225);
FORCEPROP 1 LAST BODY_TYPE PLUMBING
J 0
(-6025 3275);
DISPLAY 0.872340 (-6025 3275);
PAINT GREEN (-6025 3275);
DISPLAY INVISIBLE (-6025 3275);
FORCEPROP 1 LAST HDL_TAP TRUE
J 0
(-5700 3100);
DISPLAY 0.872340 (-5700 3100);
DISPLAY INVISIBLE (-5700 3100);
FORCEPROP 1 LAST PATH I60
J 0
(-6027 3225);
DISPLAY 0.872340 (-6027 3225);
PAINT GREEN (-6027 3225);
DISPLAY INVISIBLE (-6027 3225);
FORCEADD TAP..1
(-6025 3275);
FORCEPROP 3 LASTPIN (-6075 3275) SIG_NAME M_L_CPU0_SB_DQ<28>
J 0
(-6065 3285);
DISPLAY 0.659574 (-6065 3285);
PAINT MONO (-6065 3285);
DISPLAY INVISIBLE (-6065 3285);
FORCEPROP 1 LASTPIN (-6075 3275) BN 28
J 0
(-6087 3283);
DISPLAY 0.489362 (-6087 3283);
PAINT GREEN (-6087 3283);
FORCEPROP 2 LAST CDS_LIB mstr_standard
J 0
(-6025 3275);
DISPLAY 0.723404 (-6025 3275);
PAINT MONO (-6025 3275);
DISPLAY INVISIBLE (-6025 3275);
FORCEPROP 1 LAST BODY_TYPE PLUMBING
J 0
(-6025 3325);
DISPLAY 0.872340 (-6025 3325);
PAINT GREEN (-6025 3325);
DISPLAY INVISIBLE (-6025 3325);
FORCEPROP 1 LAST HDL_TAP TRUE
J 0
(-5700 3150);
DISPLAY 0.872340 (-5700 3150);
DISPLAY INVISIBLE (-5700 3150);
FORCEPROP 1 LAST PATH I61
J 0
(-6027 3275);
DISPLAY 0.872340 (-6027 3275);
PAINT GREEN (-6027 3275);
DISPLAY INVISIBLE (-6027 3275);
FORCEADD TAP..1
(-6025 3325);
FORCEPROP 3 LASTPIN (-6075 3325) SIG_NAME M_L_CPU0_SB_DQ<29>
J 0
(-6065 3335);
DISPLAY 0.659574 (-6065 3335);
PAINT MONO (-6065 3335);
DISPLAY INVISIBLE (-6065 3335);
FORCEPROP 1 LASTPIN (-6075 3325) BN 29
J 0
(-6087 3333);
DISPLAY 0.489362 (-6087 3333);
PAINT GREEN (-6087 3333);
FORCEPROP 2 LAST CDS_LIB mstr_standard
J 0
(-6025 3325);
DISPLAY 0.723404 (-6025 3325);
PAINT MONO (-6025 3325);
DISPLAY INVISIBLE (-6025 3325);
FORCEPROP 1 LAST BODY_TYPE PLUMBING
J 0
(-6025 3375);
DISPLAY 0.872340 (-6025 3375);
PAINT GREEN (-6025 3375);
DISPLAY INVISIBLE (-6025 3375);
FORCEPROP 1 LAST HDL_TAP TRUE
J 0
(-5700 3200);
DISPLAY 0.872340 (-5700 3200);
DISPLAY INVISIBLE (-5700 3200);
FORCEPROP 1 LAST PATH I62
J 0
(-6027 3325);
DISPLAY 0.872340 (-6027 3325);
PAINT GREEN (-6027 3325);
DISPLAY INVISIBLE (-6027 3325);
FORCEADD TAP..1
(-6025 3375);
FORCEPROP 3 LASTPIN (-6075 3375) SIG_NAME M_L_CPU0_SB_DQ<30>
J 0
(-6065 3385);
DISPLAY 0.659574 (-6065 3385);
PAINT MONO (-6065 3385);
DISPLAY INVISIBLE (-6065 3385);
FORCEPROP 1 LASTPIN (-6075 3375) BN 30
J 0
(-6087 3383);
DISPLAY 0.489362 (-6087 3383);
PAINT GREEN (-6087 3383);
FORCEPROP 2 LAST CDS_LIB mstr_standard
J 0
(-6025 3375);
DISPLAY 0.723404 (-6025 3375);
PAINT MONO (-6025 3375);
DISPLAY INVISIBLE (-6025 3375);
FORCEPROP 1 LAST BODY_TYPE PLUMBING
J 0
(-6025 3425);
DISPLAY 0.872340 (-6025 3425);
PAINT GREEN (-6025 3425);
DISPLAY INVISIBLE (-6025 3425);
FORCEPROP 1 LAST HDL_TAP TRUE
J 0
(-5700 3250);
DISPLAY 0.872340 (-5700 3250);
DISPLAY INVISIBLE (-5700 3250);
FORCEPROP 1 LAST PATH I63
J 0
(-6027 3375);
DISPLAY 0.872340 (-6027 3375);
PAINT GREEN (-6027 3375);
DISPLAY INVISIBLE (-6027 3375);
FORCEADD OFFPAGE..5
(-8150 2725);
FORCEPROP 2 LAST $XR0 21 
J 0
(-8374 2725);
DISPLAY 0.638298 (-8374 2725);
PAINT MONO (-8374 2725);
FORCEPROP 2 LAST CDS_LIB mstr_standard
J 0
(-8150 2725);
DISPLAY INVISIBLE (-8150 2725);
FORCEPROP 1 LAST OFFPAGE TRUE
J 0
(-7825 2600);
DISPLAY 0.872340 (-7825 2600);
PAINT GREEN (-7825 2600);
DISPLAY INVISIBLE (-7825 2600);
FORCEPROP 1 LAST COMMENT_BODY TRUE
J 0
(-8050 2650);
DISPLAY 0.872340 (-8050 2650);
PAINT GREEN (-8050 2650);
DISPLAY INVISIBLE (-8050 2650);
FORCEPROP 2 LAST PATH I7
J 0
(-8100 2800);
DISPLAY 1.021277 (-8100 2800);
DISPLAY INVISIBLE (-8100 2800);
FORCEADD TAP..1
R 2
(-7725 3425);
FORCEPROP 3 LASTPIN (-7675 3425) SIG_NAME M_L_CPU0_SA_CB<2>
J 0
(-7665 3435);
DISPLAY 0.659574 (-7665 3435);
PAINT MONO (-7665 3435);
DISPLAY INVISIBLE (-7665 3435);
FORCEPROP 1 LASTPIN (-7675 3425) BN 2
J 2
(-7663 3433);
DISPLAY 0.489362 (-7663 3433);
PAINT GREEN (-7663 3433);
FORCEPROP 2 LAST CDS_LIB mstr_standard
J 0
(-7725 3425);
DISPLAY 0.723404 (-7725 3425);
PAINT MONO (-7725 3425);
DISPLAY INVISIBLE (-7725 3425);
FORCEPROP 1 LAST BODY_TYPE PLUMBING
J 2
(-7725 3475);
DISPLAY 0.872340 (-7725 3475);
PAINT GREEN (-7725 3475);
DISPLAY INVISIBLE (-7725 3475);
FORCEPROP 1 LAST HDL_TAP TRUE
J 2
(-8050 3300);
DISPLAY 0.872340 (-8050 3300);
DISPLAY INVISIBLE (-8050 3300);
FORCEPROP 1 LAST PATH I71
J 2
(-7723 3425);
DISPLAY 0.872340 (-7723 3425);
PAINT GREEN (-7723 3425);
DISPLAY INVISIBLE (-7723 3425);
FORCEADD TAP..1
R 2
(-7725 3475);
FORCEPROP 3 LASTPIN (-7675 3475) SIG_NAME M_L_CPU0_SA_CB<3>
J 0
(-7665 3485);
DISPLAY 0.659574 (-7665 3485);
PAINT MONO (-7665 3485);
DISPLAY INVISIBLE (-7665 3485);
FORCEPROP 1 LASTPIN (-7675 3475) BN 3
J 2
(-7663 3483);
DISPLAY 0.489362 (-7663 3483);
PAINT GREEN (-7663 3483);
FORCEPROP 2 LAST CDS_LIB mstr_standard
J 0
(-7725 3475);
DISPLAY 0.723404 (-7725 3475);
PAINT MONO (-7725 3475);
DISPLAY INVISIBLE (-7725 3475);
FORCEPROP 1 LAST BODY_TYPE PLUMBING
J 2
(-7725 3525);
DISPLAY 0.872340 (-7725 3525);
PAINT GREEN (-7725 3525);
DISPLAY INVISIBLE (-7725 3525);
FORCEPROP 1 LAST HDL_TAP TRUE
J 2
(-8050 3350);
DISPLAY 0.872340 (-8050 3350);
DISPLAY INVISIBLE (-8050 3350);
FORCEPROP 1 LAST PATH I72
J 2
(-7723 3475);
DISPLAY 0.872340 (-7723 3475);
PAINT GREEN (-7723 3475);
DISPLAY INVISIBLE (-7723 3475);
FORCEADD TAP..1
R 2
(-7725 3575);
FORCEPROP 3 LASTPIN (-7675 3575) SIG_NAME M_L_CPU0_SA_CB<5>
J 0
(-7665 3585);
DISPLAY 0.659574 (-7665 3585);
PAINT MONO (-7665 3585);
DISPLAY INVISIBLE (-7665 3585);
FORCEPROP 1 LASTPIN (-7675 3575) BN 5
J 2
(-7663 3583);
DISPLAY 0.489362 (-7663 3583);
PAINT GREEN (-7663 3583);
FORCEPROP 2 LAST CDS_LIB mstr_standard
J 0
(-7725 3575);
DISPLAY 0.723404 (-7725 3575);
PAINT MONO (-7725 3575);
DISPLAY INVISIBLE (-7725 3575);
FORCEPROP 1 LAST BODY_TYPE PLUMBING
J 2
(-7725 3625);
DISPLAY 0.872340 (-7725 3625);
PAINT GREEN (-7725 3625);
DISPLAY INVISIBLE (-7725 3625);
FORCEPROP 1 LAST HDL_TAP TRUE
J 2
(-8050 3450);
DISPLAY 0.872340 (-8050 3450);
DISPLAY INVISIBLE (-8050 3450);
FORCEPROP 1 LAST PATH I73
J 2
(-7723 3575);
DISPLAY 0.872340 (-7723 3575);
PAINT GREEN (-7723 3575);
DISPLAY INVISIBLE (-7723 3575);
FORCEADD TAP..1
R 2
(-7725 3625);
FORCEPROP 3 LASTPIN (-7675 3625) SIG_NAME M_L_CPU0_SA_CB<6>
J 0
(-7665 3635);
DISPLAY 0.659574 (-7665 3635);
PAINT MONO (-7665 3635);
DISPLAY INVISIBLE (-7665 3635);
FORCEPROP 1 LASTPIN (-7675 3625) BN 6
J 2
(-7663 3633);
DISPLAY 0.489362 (-7663 3633);
PAINT GREEN (-7663 3633);
FORCEPROP 2 LAST CDS_LIB mstr_standard
J 0
(-7725 3625);
DISPLAY 0.723404 (-7725 3625);
PAINT MONO (-7725 3625);
DISPLAY INVISIBLE (-7725 3625);
FORCEPROP 1 LAST BODY_TYPE PLUMBING
J 2
(-7725 3675);
DISPLAY 0.872340 (-7725 3675);
PAINT GREEN (-7725 3675);
DISPLAY INVISIBLE (-7725 3675);
FORCEPROP 1 LAST HDL_TAP TRUE
J 2
(-8050 3500);
DISPLAY 0.872340 (-8050 3500);
DISPLAY INVISIBLE (-8050 3500);
FORCEPROP 1 LAST PATH I74
J 2
(-7723 3625);
DISPLAY 0.872340 (-7723 3625);
PAINT GREEN (-7723 3625);
DISPLAY INVISIBLE (-7723 3625);
FORCEADD TAP..1
R 2
(-7725 3525);
FORCEPROP 3 LASTPIN (-7675 3525) SIG_NAME M_L_CPU0_SA_CB<4>
J 0
(-7665 3535);
DISPLAY 0.659574 (-7665 3535);
PAINT MONO (-7665 3535);
DISPLAY INVISIBLE (-7665 3535);
FORCEPROP 1 LASTPIN (-7675 3525) BN 4
J 2
(-7663 3533);
DISPLAY 0.489362 (-7663 3533);
PAINT GREEN (-7663 3533);
FORCEPROP 2 LAST CDS_LIB mstr_standard
J 0
(-7725 3525);
DISPLAY 0.723404 (-7725 3525);
PAINT MONO (-7725 3525);
DISPLAY INVISIBLE (-7725 3525);
FORCEPROP 1 LAST BODY_TYPE PLUMBING
J 2
(-7725 3575);
DISPLAY 0.872340 (-7725 3575);
PAINT GREEN (-7725 3575);
DISPLAY INVISIBLE (-7725 3575);
FORCEPROP 1 LAST HDL_TAP TRUE
J 2
(-8050 3400);
DISPLAY 0.872340 (-8050 3400);
DISPLAY INVISIBLE (-8050 3400);
FORCEPROP 1 LAST PATH I75
J 2
(-7723 3525);
DISPLAY 0.872340 (-7723 3525);
PAINT GREEN (-7723 3525);
DISPLAY INVISIBLE (-7723 3525);
FORCEADD TAP..1
R 2
(-7725 3675);
FORCEPROP 3 LASTPIN (-7675 3675) SIG_NAME M_L_CPU0_SA_CB<7>
J 0
(-7665 3685);
DISPLAY 0.659574 (-7665 3685);
PAINT MONO (-7665 3685);
DISPLAY INVISIBLE (-7665 3685);
FORCEPROP 1 LASTPIN (-7675 3675) BN 7
J 2
(-7663 3683);
DISPLAY 0.489362 (-7663 3683);
PAINT GREEN (-7663 3683);
FORCEPROP 2 LAST CDS_LIB mstr_standard
J 0
(-7725 3675);
DISPLAY 0.723404 (-7725 3675);
PAINT MONO (-7725 3675);
DISPLAY INVISIBLE (-7725 3675);
FORCEPROP 1 LAST BODY_TYPE PLUMBING
J 2
(-7725 3725);
DISPLAY 0.872340 (-7725 3725);
PAINT GREEN (-7725 3725);
DISPLAY INVISIBLE (-7725 3725);
FORCEPROP 1 LAST HDL_TAP TRUE
J 2
(-8050 3550);
DISPLAY 0.872340 (-8050 3550);
DISPLAY INVISIBLE (-8050 3550);
FORCEPROP 1 LAST PATH I76
J 2
(-7723 3675);
DISPLAY 0.872340 (-7723 3675);
PAINT GREEN (-7723 3675);
DISPLAY INVISIBLE (-7723 3675);
FORCEADD TAP..1
R 2
(-7725 4375);
FORCEPROP 3 LASTPIN (-7675 4375) SIG_NAME M_L_CPU0_SB_CA<0>
J 0
(-7665 4385);
DISPLAY 0.659574 (-7665 4385);
PAINT MONO (-7665 4385);
DISPLAY INVISIBLE (-7665 4385);
FORCEPROP 1 LASTPIN (-7675 4375) BN 0
J 2
(-7663 4383);
DISPLAY 0.489362 (-7663 4383);
PAINT GREEN (-7663 4383);
FORCEPROP 2 LAST CDS_LIB mstr_standard
J 0
(-7725 4375);
DISPLAY 0.723404 (-7725 4375);
PAINT MONO (-7725 4375);
DISPLAY INVISIBLE (-7725 4375);
FORCEPROP 1 LAST BODY_TYPE PLUMBING
J 2
(-7725 4425);
DISPLAY 0.872340 (-7725 4425);
PAINT GREEN (-7725 4425);
DISPLAY INVISIBLE (-7725 4425);
FORCEPROP 1 LAST HDL_TAP TRUE
J 2
(-8050 4250);
DISPLAY 0.872340 (-8050 4250);
DISPLAY INVISIBLE (-8050 4250);
FORCEPROP 1 LAST PATH I77
J 2
(-7723 4375);
DISPLAY 0.872340 (-7723 4375);
PAINT GREEN (-7723 4375);
DISPLAY INVISIBLE (-7723 4375);
FORCEADD TAP..1
R 2
(-7725 4425);
FORCEPROP 3 LASTPIN (-7675 4425) SIG_NAME M_L_CPU0_SB_CA<1>
J 0
(-7665 4435);
DISPLAY 0.659574 (-7665 4435);
PAINT MONO (-7665 4435);
DISPLAY INVISIBLE (-7665 4435);
FORCEPROP 1 LASTPIN (-7675 4425) BN 1
J 2
(-7663 4433);
DISPLAY 0.489362 (-7663 4433);
PAINT GREEN (-7663 4433);
FORCEPROP 2 LAST CDS_LIB mstr_standard
J 0
(-7725 4425);
DISPLAY 0.723404 (-7725 4425);
PAINT MONO (-7725 4425);
DISPLAY INVISIBLE (-7725 4425);
FORCEPROP 1 LAST BODY_TYPE PLUMBING
J 2
(-7725 4475);
DISPLAY 0.872340 (-7725 4475);
PAINT GREEN (-7725 4475);
DISPLAY INVISIBLE (-7725 4475);
FORCEPROP 1 LAST HDL_TAP TRUE
J 2
(-8050 4300);
DISPLAY 0.872340 (-8050 4300);
DISPLAY INVISIBLE (-8050 4300);
FORCEPROP 1 LAST PATH I78
J 2
(-7723 4425);
DISPLAY 0.872340 (-7723 4425);
PAINT GREEN (-7723 4425);
DISPLAY INVISIBLE (-7723 4425);
FORCEADD TAP..1
R 2
(-7725 4475);
FORCEPROP 3 LASTPIN (-7675 4475) SIG_NAME M_L_CPU0_SB_CA<2>
J 0
(-7665 4485);
DISPLAY 0.659574 (-7665 4485);
PAINT MONO (-7665 4485);
DISPLAY INVISIBLE (-7665 4485);
FORCEPROP 1 LASTPIN (-7675 4475) BN 2
J 2
(-7663 4483);
DISPLAY 0.489362 (-7663 4483);
PAINT GREEN (-7663 4483);
FORCEPROP 2 LAST CDS_LIB mstr_standard
J 0
(-7725 4475);
DISPLAY 0.723404 (-7725 4475);
PAINT MONO (-7725 4475);
DISPLAY INVISIBLE (-7725 4475);
FORCEPROP 1 LAST BODY_TYPE PLUMBING
J 2
(-7725 4525);
DISPLAY 0.872340 (-7725 4525);
PAINT GREEN (-7725 4525);
DISPLAY INVISIBLE (-7725 4525);
FORCEPROP 1 LAST HDL_TAP TRUE
J 2
(-8050 4350);
DISPLAY 0.872340 (-8050 4350);
DISPLAY INVISIBLE (-8050 4350);
FORCEPROP 1 LAST PATH I79
J 2
(-7723 4475);
DISPLAY 0.872340 (-7723 4475);
PAINT GREEN (-7723 4475);
DISPLAY INVISIBLE (-7723 4475);
FORCEADD OFFPAGE..1
(-8150 2775);
FORCEPROP 2 LAST $XR0 21 
J 0
(-8401 2775);
DISPLAY 0.638298 (-8401 2775);
PAINT MONO (-8401 2775);
FORCEPROP 2 LAST CDS_LIB mstr_standard
J 0
(-8150 2775);
DISPLAY 0.808511 (-8150 2775);
DISPLAY INVISIBLE (-8150 2775);
FORCEPROP 1 LAST OFFPAGE TRUE
J 0
(-7825 2650);
DISPLAY 0.872340 (-7825 2650);
PAINT GREEN (-7825 2650);
DISPLAY INVISIBLE (-7825 2650);
FORCEPROP 1 LAST COMMENT_BODY TRUE
J 0
(-8025 2675);
DISPLAY 0.872340 (-8025 2675);
PAINT GREEN (-8025 2675);
DISPLAY INVISIBLE (-8025 2675);
FORCEPROP 2 LAST PATH I8
J 0
(-8575 2825);
DISPLAY 1.021277 (-8575 2825);
DISPLAY INVISIBLE (-8575 2825);
FORCEADD TAP..1
R 2
(-7725 4525);
FORCEPROP 3 LASTPIN (-7675 4525) SIG_NAME M_L_CPU0_SB_CA<3>
J 0
(-7665 4535);
DISPLAY 0.659574 (-7665 4535);
PAINT MONO (-7665 4535);
DISPLAY INVISIBLE (-7665 4535);
FORCEPROP 1 LASTPIN (-7675 4525) BN 3
J 2
(-7663 4533);
DISPLAY 0.489362 (-7663 4533);
PAINT GREEN (-7663 4533);
FORCEPROP 2 LAST CDS_LIB mstr_standard
J 0
(-7725 4525);
DISPLAY 0.723404 (-7725 4525);
PAINT MONO (-7725 4525);
DISPLAY INVISIBLE (-7725 4525);
FORCEPROP 1 LAST BODY_TYPE PLUMBING
J 2
(-7725 4575);
DISPLAY 0.872340 (-7725 4575);
PAINT GREEN (-7725 4575);
DISPLAY INVISIBLE (-7725 4575);
FORCEPROP 1 LAST HDL_TAP TRUE
J 2
(-8050 4400);
DISPLAY 0.872340 (-8050 4400);
DISPLAY INVISIBLE (-8050 4400);
FORCEPROP 1 LAST PATH I80
J 2
(-7723 4525);
DISPLAY 0.872340 (-7723 4525);
PAINT GREEN (-7723 4525);
DISPLAY INVISIBLE (-7723 4525);
FORCEADD TAP..1
R 2
(-7725 4575);
FORCEPROP 3 LASTPIN (-7675 4575) SIG_NAME M_L_CPU0_SB_CA<4>
J 0
(-7665 4585);
DISPLAY 0.659574 (-7665 4585);
PAINT MONO (-7665 4585);
DISPLAY INVISIBLE (-7665 4585);
FORCEPROP 1 LASTPIN (-7675 4575) BN 4
J 2
(-7663 4583);
DISPLAY 0.489362 (-7663 4583);
PAINT GREEN (-7663 4583);
FORCEPROP 2 LAST CDS_LIB mstr_standard
J 0
(-7725 4575);
DISPLAY 0.723404 (-7725 4575);
PAINT MONO (-7725 4575);
DISPLAY INVISIBLE (-7725 4575);
FORCEPROP 1 LAST BODY_TYPE PLUMBING
J 2
(-7725 4625);
DISPLAY 0.872340 (-7725 4625);
PAINT GREEN (-7725 4625);
DISPLAY INVISIBLE (-7725 4625);
FORCEPROP 1 LAST HDL_TAP TRUE
J 2
(-8050 4450);
DISPLAY 0.872340 (-8050 4450);
DISPLAY INVISIBLE (-8050 4450);
FORCEPROP 1 LAST PATH I81
J 2
(-7723 4575);
DISPLAY 0.872340 (-7723 4575);
PAINT GREEN (-7723 4575);
DISPLAY INVISIBLE (-7723 4575);
FORCEADD TAP..1
R 2
(-7725 4675);
FORCEPROP 3 LASTPIN (-7675 4675) SIG_NAME M_L_CPU0_SB_CA<6>
J 0
(-7665 4685);
DISPLAY 0.659574 (-7665 4685);
PAINT MONO (-7665 4685);
DISPLAY INVISIBLE (-7665 4685);
FORCEPROP 1 LASTPIN (-7675 4675) BN 6
J 2
(-7663 4683);
DISPLAY 0.489362 (-7663 4683);
PAINT GREEN (-7663 4683);
FORCEPROP 2 LAST CDS_LIB mstr_standard
J 0
(-7725 4675);
DISPLAY 0.723404 (-7725 4675);
PAINT MONO (-7725 4675);
DISPLAY INVISIBLE (-7725 4675);
FORCEPROP 1 LAST BODY_TYPE PLUMBING
J 2
(-7725 4725);
DISPLAY 0.872340 (-7725 4725);
PAINT GREEN (-7725 4725);
DISPLAY INVISIBLE (-7725 4725);
FORCEPROP 1 LAST HDL_TAP TRUE
J 2
(-8050 4550);
DISPLAY 0.872340 (-8050 4550);
DISPLAY INVISIBLE (-8050 4550);
FORCEPROP 1 LAST PATH I82
J 2
(-7723 4675);
DISPLAY 0.872340 (-7723 4675);
PAINT GREEN (-7723 4675);
DISPLAY INVISIBLE (-7723 4675);
FORCEADD TAP..1
R 2
(-7725 4625);
FORCEPROP 3 LASTPIN (-7675 4625) SIG_NAME M_L_CPU0_SB_CA<5>
J 0
(-7665 4635);
DISPLAY 0.659574 (-7665 4635);
PAINT MONO (-7665 4635);
DISPLAY INVISIBLE (-7665 4635);
FORCEPROP 1 LASTPIN (-7675 4625) BN 5
J 2
(-7663 4633);
DISPLAY 0.489362 (-7663 4633);
PAINT GREEN (-7663 4633);
FORCEPROP 2 LAST CDS_LIB mstr_standard
J 0
(-7725 4625);
DISPLAY 0.723404 (-7725 4625);
PAINT MONO (-7725 4625);
DISPLAY INVISIBLE (-7725 4625);
FORCEPROP 1 LAST BODY_TYPE PLUMBING
J 2
(-7725 4675);
DISPLAY 0.872340 (-7725 4675);
PAINT GREEN (-7725 4675);
DISPLAY INVISIBLE (-7725 4675);
FORCEPROP 1 LAST HDL_TAP TRUE
J 2
(-8050 4500);
DISPLAY 0.872340 (-8050 4500);
DISPLAY INVISIBLE (-8050 4500);
FORCEPROP 1 LAST PATH I83
J 2
(-7723 4625);
DISPLAY 0.872340 (-7723 4625);
PAINT GREEN (-7723 4625);
DISPLAY INVISIBLE (-7723 4625);
FORCEADD TAP..1
R 2
(-7725 4825);
FORCEPROP 3 LASTPIN (-7675 4825) SIG_NAME M_L_CPU0_SA_CA<1>
J 0
(-7665 4835);
DISPLAY 0.659574 (-7665 4835);
PAINT MONO (-7665 4835);
DISPLAY INVISIBLE (-7665 4835);
FORCEPROP 1 LASTPIN (-7675 4825) BN 1
J 2
(-7663 4833);
DISPLAY 0.489362 (-7663 4833);
PAINT GREEN (-7663 4833);
FORCEPROP 2 LAST CDS_LIB mstr_standard
J 0
(-7725 4825);
DISPLAY 0.723404 (-7725 4825);
PAINT MONO (-7725 4825);
DISPLAY INVISIBLE (-7725 4825);
FORCEPROP 1 LAST BODY_TYPE PLUMBING
J 2
(-7725 4875);
DISPLAY 0.872340 (-7725 4875);
PAINT GREEN (-7725 4875);
DISPLAY INVISIBLE (-7725 4875);
FORCEPROP 1 LAST HDL_TAP TRUE
J 2
(-8050 4700);
DISPLAY 0.872340 (-8050 4700);
DISPLAY INVISIBLE (-8050 4700);
FORCEPROP 1 LAST PATH I84
J 2
(-7723 4825);
DISPLAY 0.872340 (-7723 4825);
PAINT GREEN (-7723 4825);
DISPLAY INVISIBLE (-7723 4825);
FORCEADD TAP..1
R 2
(-7725 4875);
FORCEPROP 3 LASTPIN (-7675 4875) SIG_NAME M_L_CPU0_SA_CA<2>
J 0
(-7665 4885);
DISPLAY 0.659574 (-7665 4885);
PAINT MONO (-7665 4885);
DISPLAY INVISIBLE (-7665 4885);
FORCEPROP 1 LASTPIN (-7675 4875) BN 2
J 2
(-7663 4883);
DISPLAY 0.489362 (-7663 4883);
PAINT GREEN (-7663 4883);
FORCEPROP 2 LAST CDS_LIB mstr_standard
J 0
(-7725 4875);
DISPLAY 0.723404 (-7725 4875);
PAINT MONO (-7725 4875);
DISPLAY INVISIBLE (-7725 4875);
FORCEPROP 1 LAST BODY_TYPE PLUMBING
J 2
(-7725 4925);
DISPLAY 0.872340 (-7725 4925);
PAINT GREEN (-7725 4925);
DISPLAY INVISIBLE (-7725 4925);
FORCEPROP 1 LAST HDL_TAP TRUE
J 2
(-8050 4750);
DISPLAY 0.872340 (-8050 4750);
DISPLAY INVISIBLE (-8050 4750);
FORCEPROP 1 LAST PATH I85
J 2
(-7723 4875);
DISPLAY 0.872340 (-7723 4875);
PAINT GREEN (-7723 4875);
DISPLAY INVISIBLE (-7723 4875);
FORCEADD TAP..1
R 2
(-7725 4925);
FORCEPROP 3 LASTPIN (-7675 4925) SIG_NAME M_L_CPU0_SA_CA<3>
J 0
(-7665 4935);
DISPLAY 0.659574 (-7665 4935);
PAINT MONO (-7665 4935);
DISPLAY INVISIBLE (-7665 4935);
FORCEPROP 1 LASTPIN (-7675 4925) BN 3
J 2
(-7663 4933);
DISPLAY 0.489362 (-7663 4933);
PAINT GREEN (-7663 4933);
FORCEPROP 2 LAST CDS_LIB mstr_standard
J 0
(-7725 4925);
DISPLAY 0.723404 (-7725 4925);
PAINT MONO (-7725 4925);
DISPLAY INVISIBLE (-7725 4925);
FORCEPROP 1 LAST BODY_TYPE PLUMBING
J 2
(-7725 4975);
DISPLAY 0.872340 (-7725 4975);
PAINT GREEN (-7725 4975);
DISPLAY INVISIBLE (-7725 4975);
FORCEPROP 1 LAST HDL_TAP TRUE
J 2
(-8050 4800);
DISPLAY 0.872340 (-8050 4800);
DISPLAY INVISIBLE (-8050 4800);
FORCEPROP 1 LAST PATH I86
J 2
(-7723 4925);
DISPLAY 0.872340 (-7723 4925);
PAINT GREEN (-7723 4925);
DISPLAY INVISIBLE (-7723 4925);
FORCEADD TAP..1
R 2
(-7725 4775);
FORCEPROP 3 LASTPIN (-7675 4775) SIG_NAME M_L_CPU0_SA_CA<0>
J 0
(-7665 4785);
DISPLAY 0.659574 (-7665 4785);
PAINT MONO (-7665 4785);
DISPLAY INVISIBLE (-7665 4785);
FORCEPROP 1 LASTPIN (-7675 4775) BN 0
J 2
(-7663 4783);
DISPLAY 0.489362 (-7663 4783);
PAINT GREEN (-7663 4783);
FORCEPROP 2 LAST CDS_LIB mstr_standard
J 0
(-7725 4775);
DISPLAY 0.723404 (-7725 4775);
PAINT MONO (-7725 4775);
DISPLAY INVISIBLE (-7725 4775);
FORCEPROP 1 LAST BODY_TYPE PLUMBING
J 2
(-7725 4825);
DISPLAY 0.872340 (-7725 4825);
PAINT GREEN (-7725 4825);
DISPLAY INVISIBLE (-7725 4825);
FORCEPROP 1 LAST HDL_TAP TRUE
J 2
(-8050 4650);
DISPLAY 0.872340 (-8050 4650);
DISPLAY INVISIBLE (-8050 4650);
FORCEPROP 1 LAST PATH I87
J 2
(-7723 4775);
DISPLAY 0.872340 (-7723 4775);
PAINT GREEN (-7723 4775);
DISPLAY INVISIBLE (-7723 4775);
FORCEADD TAP..1
R 2
(-7725 5025);
FORCEPROP 3 LASTPIN (-7675 5025) SIG_NAME M_L_CPU0_SA_CA<5>
J 0
(-7665 5035);
DISPLAY 0.659574 (-7665 5035);
PAINT MONO (-7665 5035);
DISPLAY INVISIBLE (-7665 5035);
FORCEPROP 1 LASTPIN (-7675 5025) BN 5
J 2
(-7663 5033);
DISPLAY 0.489362 (-7663 5033);
PAINT GREEN (-7663 5033);
FORCEPROP 2 LAST CDS_LIB mstr_standard
J 0
(-7725 5025);
DISPLAY 0.723404 (-7725 5025);
PAINT MONO (-7725 5025);
DISPLAY INVISIBLE (-7725 5025);
FORCEPROP 1 LAST BODY_TYPE PLUMBING
J 2
(-7725 5075);
DISPLAY 0.872340 (-7725 5075);
PAINT GREEN (-7725 5075);
DISPLAY INVISIBLE (-7725 5075);
FORCEPROP 1 LAST HDL_TAP TRUE
J 2
(-8050 4900);
DISPLAY 0.872340 (-8050 4900);
DISPLAY INVISIBLE (-8050 4900);
FORCEPROP 1 LAST PATH I88
J 2
(-7723 5025);
DISPLAY 0.872340 (-7723 5025);
PAINT GREEN (-7723 5025);
DISPLAY INVISIBLE (-7723 5025);
FORCEADD TAP..1
R 2
(-7725 5075);
FORCEPROP 3 LASTPIN (-7675 5075) SIG_NAME M_L_CPU0_SA_CA<6>
J 0
(-7665 5085);
DISPLAY 0.659574 (-7665 5085);
PAINT MONO (-7665 5085);
DISPLAY INVISIBLE (-7665 5085);
FORCEPROP 1 LASTPIN (-7675 5075) BN 6
J 2
(-7663 5083);
DISPLAY 0.489362 (-7663 5083);
PAINT GREEN (-7663 5083);
FORCEPROP 2 LAST CDS_LIB mstr_standard
J 0
(-7725 5075);
DISPLAY 0.723404 (-7725 5075);
PAINT MONO (-7725 5075);
DISPLAY INVISIBLE (-7725 5075);
FORCEPROP 1 LAST BODY_TYPE PLUMBING
J 2
(-7725 5125);
DISPLAY 0.872340 (-7725 5125);
PAINT GREEN (-7725 5125);
DISPLAY INVISIBLE (-7725 5125);
FORCEPROP 1 LAST HDL_TAP TRUE
J 2
(-8050 4950);
DISPLAY 0.872340 (-8050 4950);
DISPLAY INVISIBLE (-8050 4950);
FORCEPROP 1 LAST PATH I89
J 2
(-7723 5075);
DISPLAY 0.872340 (-7723 5075);
PAINT GREEN (-7723 5075);
DISPLAY INVISIBLE (-7723 5075);
FORCEADD VCC_CORE..1
(-8500 3100);
FORCEPROP 3 LASTPIN (-8500 3050) SIG_NAME P3V3_STBY\g
J 0
(-8490 3060);
DISPLAY 0.659574 (-8490 3060);
PAINT MONO (-8490 3060);
DISPLAY INVISIBLE (-8490 3060);
FORCEPROP 1 LAST HDL_POWER P3V3_STBY
J 1
(-8500 3150);
DISPLAY 0.489362 (-8500 3150);
PAINT GREEN (-8500 3150);
FORCEPROP 2 LAST CDS_LIB mstr_symbols
J 0
(-8500 3100);
PAINT MONO (-8500 3100);
DISPLAY INVISIBLE (-8500 3100);
FORCEPROP 1 LAST PATH I9
J 0
(-8450 3125);
DISPLAY 0.872340 (-8450 3125);
PAINT AQUA (-8450 3125);
DISPLAY INVISIBLE (-8450 3125);
FORCEPROP 0 LAST VOLTAGE 3.3
J 0
(-8775 3250);
DISPLAY 1.021277 (-8775 3250);
PAINT SKYBLUE (-8775 3250);
DISPLAY INVISIBLE (-8775 3250);
FORCEPROP 2 LAST ROOM PVCCINFAON_CPU0_CTRL
J 0
(-8500 3200);
DISPLAY 0.808511 (-8500 3200);
PAINT RED (-8500 3200);
DISPLAY INVISIBLE (-8500 3200);
FORCEADD TAP..1
R 2
(-7725 4975);
FORCEPROP 3 LASTPIN (-7675 4975) SIG_NAME M_L_CPU0_SA_CA<4>
J 0
(-7665 4985);
DISPLAY 0.659574 (-7665 4985);
PAINT MONO (-7665 4985);
DISPLAY INVISIBLE (-7665 4985);
FORCEPROP 1 LASTPIN (-7675 4975) BN 4
J 2
(-7663 4983);
DISPLAY 0.489362 (-7663 4983);
PAINT GREEN (-7663 4983);
FORCEPROP 2 LAST CDS_LIB mstr_standard
J 0
(-7725 4975);
DISPLAY 0.723404 (-7725 4975);
PAINT MONO (-7725 4975);
DISPLAY INVISIBLE (-7725 4975);
FORCEPROP 1 LAST BODY_TYPE PLUMBING
J 2
(-7725 5025);
DISPLAY 0.872340 (-7725 5025);
PAINT GREEN (-7725 5025);
DISPLAY INVISIBLE (-7725 5025);
FORCEPROP 1 LAST HDL_TAP TRUE
J 2
(-8050 4850);
DISPLAY 0.872340 (-8050 4850);
DISPLAY INVISIBLE (-8050 4850);
FORCEPROP 1 LAST PATH I90
J 2
(-7723 4975);
DISPLAY 0.872340 (-7723 4975);
PAINT GREEN (-7723 4975);
DISPLAY INVISIBLE (-7723 4975);
FORCEADD TAP..1
(-6025 3425);
FORCEPROP 3 LASTPIN (-6075 3425) SIG_NAME M_L_CPU0_SB_DQ<31>
J 0
(-6065 3435);
DISPLAY 0.659574 (-6065 3435);
PAINT MONO (-6065 3435);
DISPLAY INVISIBLE (-6065 3435);
FORCEPROP 1 LASTPIN (-6075 3425) BN 31
J 0
(-6087 3433);
DISPLAY 0.489362 (-6087 3433);
PAINT GREEN (-6087 3433);
FORCEPROP 2 LAST CDS_LIB mstr_standard
J 0
(-6025 3425);
DISPLAY 0.723404 (-6025 3425);
PAINT MONO (-6025 3425);
DISPLAY INVISIBLE (-6025 3425);
FORCEPROP 1 LAST BODY_TYPE PLUMBING
J 0
(-6025 3475);
DISPLAY 0.872340 (-6025 3475);
PAINT GREEN (-6025 3475);
DISPLAY INVISIBLE (-6025 3475);
FORCEPROP 1 LAST HDL_TAP TRUE
J 0
(-5700 3300);
DISPLAY 0.872340 (-5700 3300);
DISPLAY INVISIBLE (-5700 3300);
FORCEPROP 1 LAST PATH I91
J 0
(-6027 3425);
DISPLAY 0.872340 (-6027 3425);
PAINT GREEN (-6027 3425);
DISPLAY INVISIBLE (-6027 3425);
FORCEADD TAP..1
(-6025 3525);
FORCEPROP 3 LASTPIN (-6075 3525) SIG_NAME M_L_CPU0_SA_DQ<0>
J 0
(-6065 3535);
DISPLAY 0.659574 (-6065 3535);
PAINT MONO (-6065 3535);
DISPLAY INVISIBLE (-6065 3535);
FORCEPROP 1 LASTPIN (-6075 3525) BN 0
J 0
(-6087 3533);
DISPLAY 0.489362 (-6087 3533);
PAINT GREEN (-6087 3533);
FORCEPROP 2 LAST CDS_LIB mstr_standard
J 0
(-6025 3525);
DISPLAY 0.723404 (-6025 3525);
PAINT MONO (-6025 3525);
DISPLAY INVISIBLE (-6025 3525);
FORCEPROP 1 LAST BODY_TYPE PLUMBING
J 0
(-6025 3575);
DISPLAY 0.872340 (-6025 3575);
PAINT GREEN (-6025 3575);
DISPLAY INVISIBLE (-6025 3575);
FORCEPROP 1 LAST HDL_TAP TRUE
J 0
(-5700 3400);
DISPLAY 0.872340 (-5700 3400);
DISPLAY INVISIBLE (-5700 3400);
FORCEPROP 1 LAST PATH I92
J 0
(-6027 3525);
DISPLAY 0.872340 (-6027 3525);
PAINT GREEN (-6027 3525);
DISPLAY INVISIBLE (-6027 3525);
FORCEADD TAP..1
(-6025 3575);
FORCEPROP 3 LASTPIN (-6075 3575) SIG_NAME M_L_CPU0_SA_DQ<1>
J 0
(-6065 3585);
DISPLAY 0.659574 (-6065 3585);
PAINT MONO (-6065 3585);
DISPLAY INVISIBLE (-6065 3585);
FORCEPROP 1 LASTPIN (-6075 3575) BN 1
J 0
(-6087 3583);
DISPLAY 0.489362 (-6087 3583);
PAINT GREEN (-6087 3583);
FORCEPROP 2 LAST CDS_LIB mstr_standard
J 0
(-6025 3575);
DISPLAY 0.723404 (-6025 3575);
PAINT MONO (-6025 3575);
DISPLAY INVISIBLE (-6025 3575);
FORCEPROP 1 LAST BODY_TYPE PLUMBING
J 0
(-6025 3625);
DISPLAY 0.872340 (-6025 3625);
PAINT GREEN (-6025 3625);
DISPLAY INVISIBLE (-6025 3625);
FORCEPROP 1 LAST HDL_TAP TRUE
J 0
(-5700 3450);
DISPLAY 0.872340 (-5700 3450);
DISPLAY INVISIBLE (-5700 3450);
FORCEPROP 1 LAST PATH I93
J 0
(-6027 3575);
DISPLAY 0.872340 (-6027 3575);
PAINT GREEN (-6027 3575);
DISPLAY INVISIBLE (-6027 3575);
FORCEADD TAP..1
(-6025 3625);
FORCEPROP 3 LASTPIN (-6075 3625) SIG_NAME M_L_CPU0_SA_DQ<2>
J 0
(-6065 3635);
DISPLAY 0.659574 (-6065 3635);
PAINT MONO (-6065 3635);
DISPLAY INVISIBLE (-6065 3635);
FORCEPROP 1 LASTPIN (-6075 3625) BN 2
J 0
(-6087 3633);
DISPLAY 0.489362 (-6087 3633);
PAINT GREEN (-6087 3633);
FORCEPROP 2 LAST CDS_LIB mstr_standard
J 0
(-6025 3625);
DISPLAY 0.723404 (-6025 3625);
PAINT MONO (-6025 3625);
DISPLAY INVISIBLE (-6025 3625);
FORCEPROP 1 LAST BODY_TYPE PLUMBING
J 0
(-6025 3675);
DISPLAY 0.872340 (-6025 3675);
PAINT GREEN (-6025 3675);
DISPLAY INVISIBLE (-6025 3675);
FORCEPROP 1 LAST HDL_TAP TRUE
J 0
(-5700 3500);
DISPLAY 0.872340 (-5700 3500);
DISPLAY INVISIBLE (-5700 3500);
FORCEPROP 1 LAST PATH I94
J 0
(-6027 3625);
DISPLAY 0.872340 (-6027 3625);
PAINT GREEN (-6027 3625);
DISPLAY INVISIBLE (-6027 3625);
FORCEADD TAP..1
(-6025 3675);
FORCEPROP 3 LASTPIN (-6075 3675) SIG_NAME M_L_CPU0_SA_DQ<3>
J 0
(-6065 3685);
DISPLAY 0.659574 (-6065 3685);
PAINT MONO (-6065 3685);
DISPLAY INVISIBLE (-6065 3685);
FORCEPROP 1 LASTPIN (-6075 3675) BN 3
J 0
(-6087 3683);
DISPLAY 0.489362 (-6087 3683);
PAINT GREEN (-6087 3683);
FORCEPROP 2 LAST CDS_LIB mstr_standard
J 0
(-6025 3675);
DISPLAY 0.723404 (-6025 3675);
PAINT MONO (-6025 3675);
DISPLAY INVISIBLE (-6025 3675);
FORCEPROP 1 LAST BODY_TYPE PLUMBING
J 0
(-6025 3725);
DISPLAY 0.872340 (-6025 3725);
PAINT GREEN (-6025 3725);
DISPLAY INVISIBLE (-6025 3725);
FORCEPROP 1 LAST HDL_TAP TRUE
J 0
(-5700 3550);
DISPLAY 0.872340 (-5700 3550);
DISPLAY INVISIBLE (-5700 3550);
FORCEPROP 1 LAST PATH I95
J 0
(-6027 3675);
DISPLAY 0.872340 (-6027 3675);
PAINT GREEN (-6027 3675);
DISPLAY INVISIBLE (-6027 3675);
FORCEADD TAP..1
(-6025 3725);
FORCEPROP 3 LASTPIN (-6075 3725) SIG_NAME M_L_CPU0_SA_DQ<4>
J 0
(-6065 3735);
DISPLAY 0.659574 (-6065 3735);
PAINT MONO (-6065 3735);
DISPLAY INVISIBLE (-6065 3735);
FORCEPROP 1 LASTPIN (-6075 3725) BN 4
J 0
(-6087 3733);
DISPLAY 0.489362 (-6087 3733);
PAINT GREEN (-6087 3733);
FORCEPROP 2 LAST CDS_LIB mstr_standard
J 0
(-6025 3725);
DISPLAY 0.723404 (-6025 3725);
PAINT MONO (-6025 3725);
DISPLAY INVISIBLE (-6025 3725);
FORCEPROP 1 LAST BODY_TYPE PLUMBING
J 0
(-6025 3775);
DISPLAY 0.872340 (-6025 3775);
PAINT GREEN (-6025 3775);
DISPLAY INVISIBLE (-6025 3775);
FORCEPROP 1 LAST HDL_TAP TRUE
J 0
(-5700 3600);
DISPLAY 0.872340 (-5700 3600);
DISPLAY INVISIBLE (-5700 3600);
FORCEPROP 1 LAST PATH I96
J 0
(-6027 3725);
DISPLAY 0.872340 (-6027 3725);
PAINT GREEN (-6027 3725);
DISPLAY INVISIBLE (-6027 3725);
FORCEADD TAP..1
(-6025 3775);
FORCEPROP 3 LASTPIN (-6075 3775) SIG_NAME M_L_CPU0_SA_DQ<5>
J 0
(-6065 3785);
DISPLAY 0.659574 (-6065 3785);
PAINT MONO (-6065 3785);
DISPLAY INVISIBLE (-6065 3785);
FORCEPROP 1 LASTPIN (-6075 3775) BN 5
J 0
(-6087 3783);
DISPLAY 0.489362 (-6087 3783);
PAINT GREEN (-6087 3783);
FORCEPROP 2 LAST CDS_LIB mstr_standard
J 0
(-6025 3775);
DISPLAY 0.723404 (-6025 3775);
PAINT MONO (-6025 3775);
DISPLAY INVISIBLE (-6025 3775);
FORCEPROP 1 LAST BODY_TYPE PLUMBING
J 0
(-6025 3825);
DISPLAY 0.872340 (-6025 3825);
PAINT GREEN (-6025 3825);
DISPLAY INVISIBLE (-6025 3825);
FORCEPROP 1 LAST HDL_TAP TRUE
J 0
(-5700 3650);
DISPLAY 0.872340 (-5700 3650);
DISPLAY INVISIBLE (-5700 3650);
FORCEPROP 1 LAST PATH I97
J 0
(-6027 3775);
DISPLAY 0.872340 (-6027 3775);
PAINT GREEN (-6027 3775);
DISPLAY INVISIBLE (-6027 3775);
FORCEADD TAP..1
(-6025 3825);
FORCEPROP 3 LASTPIN (-6075 3825) SIG_NAME M_L_CPU0_SA_DQ<6>
J 0
(-6065 3835);
DISPLAY 0.659574 (-6065 3835);
PAINT MONO (-6065 3835);
DISPLAY INVISIBLE (-6065 3835);
FORCEPROP 1 LASTPIN (-6075 3825) BN 6
J 0
(-6087 3833);
DISPLAY 0.489362 (-6087 3833);
PAINT GREEN (-6087 3833);
FORCEPROP 2 LAST CDS_LIB mstr_standard
J 0
(-6025 3825);
DISPLAY 0.723404 (-6025 3825);
PAINT MONO (-6025 3825);
DISPLAY INVISIBLE (-6025 3825);
FORCEPROP 1 LAST BODY_TYPE PLUMBING
J 0
(-6025 3875);
DISPLAY 0.872340 (-6025 3875);
PAINT GREEN (-6025 3875);
DISPLAY INVISIBLE (-6025 3875);
FORCEPROP 1 LAST HDL_TAP TRUE
J 0
(-5700 3700);
DISPLAY 0.872340 (-5700 3700);
DISPLAY INVISIBLE (-5700 3700);
FORCEPROP 1 LAST PATH I98
J 0
(-6027 3825);
DISPLAY 0.872340 (-6027 3825);
PAINT GREEN (-6027 3825);
DISPLAY INVISIBLE (-6027 3825);
FORCEADD TAP..1
(-6025 3875);
FORCEPROP 3 LASTPIN (-6075 3875) SIG_NAME M_L_CPU0_SA_DQ<7>
J 0
(-6065 3885);
DISPLAY 0.659574 (-6065 3885);
PAINT MONO (-6065 3885);
DISPLAY INVISIBLE (-6065 3885);
FORCEPROP 1 LASTPIN (-6075 3875) BN 7
J 0
(-6087 3883);
DISPLAY 0.489362 (-6087 3883);
PAINT GREEN (-6087 3883);
FORCEPROP 2 LAST CDS_LIB mstr_standard
J 0
(-6025 3875);
DISPLAY 0.723404 (-6025 3875);
PAINT MONO (-6025 3875);
DISPLAY INVISIBLE (-6025 3875);
FORCEPROP 1 LAST BODY_TYPE PLUMBING
J 0
(-6025 3925);
DISPLAY 0.872340 (-6025 3925);
PAINT GREEN (-6025 3925);
DISPLAY INVISIBLE (-6025 3925);
FORCEPROP 1 LAST HDL_TAP TRUE
J 0
(-5700 3750);
DISPLAY 0.872340 (-5700 3750);
DISPLAY INVISIBLE (-5700 3750);
FORCEPROP 1 LAST PATH I99
J 0
(-6027 3875);
DISPLAY 0.872340 (-6027 3875);
PAINT GREEN (-6027 3875);
DISPLAY INVISIBLE (-6027 3875);
FORCEADD QUANTA_TITLE_BLOCK_C..1
(0 0);
FORCEPROP 0 LAST CDS_CON_LAST_MODIFIED Fri Mar 11 14:53:00 2022
J 0
(-1885 15);
DISPLAY INVISIBLE (-1885 15);
FORCEPROP 1 LAST CUSTOM_TXT_CDS <CON_LAST_MODIFIED>
J 0
(-1885 15);
DISPLAY 0.978723 (-1885 15);
FORCEPROP 2 LAST CUSTOM_TXT_CDS <XR_PAGE_TITLE>
J 0
(-7890 5250);
DISPLAY 0.638298 (-7890 5250);
PAINT PINK (-7890 5250);
DISPLAY INVISIBLE (-7890 5250);
FORCEPROP 1 LAST CUSTOM_TXT_CDS <NAME_2>
J 0
(-3175 50);
FORCEPROP 1 LAST CUSTOM_TXT_CDS <NAME_1>
J 0
(-3175 175);
FORCEPROP 1 LAST CUSTOM_TXT_CDS <Q_NUMBER>
J 0
(-1403 103);
DISPLAY 1.212766 (-1403 103);
FORCEPROP 1 LAST CUSTOM_TXT_CDS <Q_PROJ>
J 0
(-2382 102);
DISPLAY 1.212766 (-2382 102);
FORCEPROP 1 LAST CUSTOM_TXT_CDS <Q_REV>
J 0
(-184 103);
DISPLAY 1.212766 (-184 103);
FORCEPROP 1 LAST CUSTOM_TXT_CDS <CON_PAGE_NUM> OF <CON_TOTAL_PAGES>
J 0
(-446 18);
DISPLAY 0.978723 (-446 18);
FORCEPROP 1 LAST Q_DEPT BU9
J 1
(-3763 49);
DISPLAY 1.957447 (-3763 49);
PAINT GREEN (-3763 49);
FORCEPROP 1 LAST Q_TITLE DDR5 - CPU0 CHL
J 0
(-9366 26);
DISPLAY 2.446809 (-9366 26);
PAINT GREEN (-9366 26);
FORCEPROP 2 LAST CDS_LIB pure_quanta
J 0
(0 0);
DISPLAY INVISIBLE (0 0);
FORCEPROP 1 LAST CDS_LMAN_SYM_OUTLINE -9475,6775,100,-125
J 0
(0 0);
DISPLAY 0.468085 (0 0);
PAINT GREEN (0 0);
DISPLAY INVISIBLE (0 0);
FORCEPROP 2 LAST PAGE_BORDER TRUE
J 0
(-7890 5250);
DISPLAY 0.638298 (-7890 5250);
PAINT PINK (-7890 5250);
DISPLAY INVISIBLE (-7890 5250);
FORCEPROP 1 LAST COMMENT_BODY TRUE
J 0
(12 -13);
DISPLAY 0.978723 (12 -13);
PAINT GREEN (12 -13);
DISPLAY INVISIBLE (12 -13);
FORCEPROP 2 LAST CDS_XR_PAGE_TITLE CR-96 : @T6G_MB_LIB.T6G(SCH_1):PAGE96
J 0
(-7890 5250);
DISPLAY 0.638298 (-7890 5250);
PAINT PINK (-7890 5250);
DISPLAY INVISIBLE (-7890 5250);
FORCEADD DNS..2
(-8325 1975);
PAINT RED (-8325 1975);
FORCEPROP 2 LAST CDS_LIB mstr_misc
J 0
(-8325 1975);
DISPLAY INVISIBLE (-8325 1975);
FORCEPROP 1 LAST COMMENT_BODY TRUE
R 1
J 0
(-8250 1750);
DISPLAY 0.872340 (-8250 1750);
PAINT PEACH (-8250 1750);
DISPLAY INVISIBLE (-8250 1750);
WIRE 17 -1 (-7775 3700)(-7775 3650);
WIRE 17 -1 (-7775 3700)(-7775 3725);
WIRE 17 -1 (-7775 3600)(-7775 3650);
WIRE 17 -1 (-7775 3600)(-7775 3550);
WIRE 17 -1 (-7775 3725)(-8275 3725);
FORCEPROP 2 LAST SIG_NAME M_L_CPU0_SA_CB<7:0>
J 0
(-8225 3735);
DISPLAY 0.489362 (-8225 3735);
WIRE 17 -1 (-7775 3500)(-7775 3550);
WIRE 17 -1 (-7775 3450)(-7775 3500);
WIRE 17 -1 (-7775 3400)(-7775 3450);
WIRE 17 -1 (-7775 3350)(-7775 3400);
WIRE 17 -1 (-7775 3250)(-7775 3200);
WIRE 17 -1 (-7775 3250)(-7775 3275);
WIRE 17 -1 (-7775 3150)(-7775 3200);
WIRE 17 -1 (-7775 3150)(-7775 3100);
WIRE 17 -1 (-7775 3275)(-8275 3275);
FORCEPROP 2 LAST SIG_NAME M_L_CPU0_SB_CB<7:0>
J 0
(-8225 3285);
DISPLAY 0.489362 (-8225 3285);
WIRE 17 -1 (-7775 4800)(-7775 4850);
WIRE 17 -1 (-7775 4850)(-7775 4900);
WIRE 17 -1 (-7775 4900)(-7775 4950);
WIRE 17 -1 (-7775 4950)(-7775 5000);
WIRE 17 -1 (-7775 5000)(-7775 5050);
WIRE 17 -1 (-7775 5050)(-7775 5100);
WIRE 17 -1 (-7775 5100)(-7775 5125);
WIRE 17 -1 (-7775 5125)(-8275 5125);
FORCEPROP 2 LAST SIG_NAME M_L_CPU0_SA_CA<6:0>
J 0
(-8260 5135);
DISPLAY 0.489362 (-8260 5135);
WIRE 17 -1 (-7775 4400)(-7775 4450);
WIRE 17 -1 (-7775 4450)(-7775 4500);
WIRE 17 -1 (-7775 4500)(-7775 4550);
WIRE 17 -1 (-7775 4550)(-7775 4600);
WIRE 17 -1 (-7775 4600)(-7775 4650);
WIRE 17 -1 (-7775 4650)(-7775 4700);
WIRE 17 -1 (-7775 4700)(-7775 4725);
WIRE 17 -1 (-7775 4725)(-8275 4725);
FORCEPROP 2 LAST SIG_NAME M_L_CPU0_SB_CA<6:0>
J 0
(-8260 4735);
DISPLAY 0.489362 (-8260 4735);
WIRE 17 -1 (-7775 3050)(-7775 3100);
WIRE 17 -1 (-7775 3000)(-7775 3050);
WIRE 17 -1 (-7775 2950)(-7775 3000);
WIRE 17 -1 (-7775 2900)(-7775 2950);
WIRE 17 -1 (-5975 5000)(-5975 4950);
WIRE 17 -1 (-5975 5050)(-5975 5000);
WIRE 17 -1 (-5975 4950)(-5975 4900);
WIRE 17 -1 (-5975 4900)(-5975 4850);
WIRE 17 -1 (-5975 5100)(-5975 5050);
WIRE 17 -1 (-5975 5100)(-5400 5100);
FORCEPROP 2 LAST SIG_NAME M_L_CPU0_SA_DQ<31:0>
J 0
(-5910 5110);
DISPLAY 0.489362 (-5910 5110);
WIRE 17 -1 (-5975 4850)(-5975 4800);
WIRE 17 -1 (-5975 4800)(-5975 4750);
WIRE 17 -1 (-5975 4750)(-5975 4700);
WIRE 17 -1 (-5975 4700)(-5975 4650);
WIRE 17 -1 (-5975 4650)(-5975 4600);
WIRE 17 -1 (-5975 4600)(-5975 4550);
WIRE 17 -1 (-5975 4550)(-5975 4500);
WIRE 17 -1 (-5975 4500)(-5975 4450);
WIRE 17 -1 (-5975 4450)(-5975 4400);
WIRE 17 -1 (-5975 4400)(-5975 4350);
WIRE 17 -1 (-5975 4300)(-5975 4350);
WIRE 17 -1 (-5975 4250)(-5975 4300);
WIRE 17 -1 (-5975 4200)(-5975 4250);
WIRE 17 -1 (-5975 4150)(-5975 4200);
WIRE 17 -1 (-5975 4150)(-5975 4100);
WIRE 17 -1 (-5975 4100)(-5975 4050);
WIRE 17 -1 (-5975 4050)(-5975 4000);
WIRE 17 -1 (-5975 4000)(-5975 3950);
WIRE 17 -1 (-5975 3950)(-5975 3900);
WIRE 17 -1 (-5975 3900)(-5975 3850);
WIRE 17 -1 (-5975 3850)(-5975 3800);
WIRE 17 -1 (-5975 3800)(-5975 3750);
WIRE 17 -1 (-5975 3700)(-5975 3750);
WIRE 17 -1 (-5975 3650)(-5975 3700);
WIRE 17 -1 (-5975 3600)(-5975 3650);
WIRE 17 -1 (-5975 3550)(-5975 3600);
WIRE 17 -1 (-5975 3450)(-5975 3400);
WIRE 17 -1 (-5975 3450)(-5400 3450);
FORCEPROP 2 LAST SIG_NAME M_L_CPU0_SB_DQ<31:0>
J 0
(-5910 3460);
DISPLAY 0.489362 (-5910 3460);
WIRE 17 -1 (-5975 3400)(-5975 3350);
WIRE 17 -1 (-5975 3350)(-5975 3300);
WIRE 17 -1 (-5975 3300)(-5975 3250);
WIRE 17 -1 (-5975 3250)(-5975 3200);
WIRE 17 -1 (-5975 3200)(-5975 3150);
WIRE 17 -1 (-5975 3150)(-5975 3100);
WIRE 17 -1 (-5975 3100)(-5975 3050);
WIRE 17 -1 (-5975 3050)(-5975 3000);
WIRE 17 -1 (-5975 3000)(-5975 2950);
WIRE 17 -1 (-5975 2950)(-5975 2900);
WIRE 17 -1 (-5975 2900)(-5975 2850);
WIRE 17 -1 (-5975 2850)(-5975 2800);
WIRE 17 -1 (-5975 2800)(-5975 2750);
WIRE 17 -1 (-5975 2750)(-5975 2700);
WIRE 17 -1 (-5975 2650)(-5975 2700);
WIRE 17 -1 (-5975 2600)(-5975 2650);
WIRE 17 -1 (-5975 2550)(-5975 2600);
WIRE 17 -1 (-5975 2500)(-5975 2550);
WIRE 17 -1 (-5975 2500)(-5975 2450);
WIRE 17 -1 (-5975 2450)(-5975 2400);
WIRE 17 -1 (-5975 2400)(-5975 2350);
WIRE 17 -1 (-5975 2350)(-5975 2300);
WIRE 17 -1 (-5975 2300)(-5975 2250);
WIRE 17 -1 (-5975 2250)(-5975 2200);
WIRE 17 -1 (-5975 2200)(-5975 2150);
WIRE 17 -1 (-5975 2150)(-5975 2100);
WIRE 17 -1 (-5975 2050)(-5975 2100);
WIRE 17 -1 (-5975 2000)(-5975 2050);
WIRE 17 -1 (-5975 1950)(-5975 2000);
WIRE 17 -1 (-5975 1900)(-5975 1950);
WIRE 17 -1 (-3250 4075)(-3250 3975);
WIRE 17 -1 (-3250 4175)(-3250 4075);
WIRE 17 -1 (-3250 3975)(-3250 3875);
WIRE 17 -1 (-3250 3775)(-3250 3875);
WIRE 17 -1 (-3250 4275)(-3250 4175);
WIRE 17 -1 (-3250 4300)(-3250 4275);
WIRE 17 -1 (-3250 3675)(-3250 3775);
WIRE 17 -1 (-3250 3575)(-3250 3675);
WIRE 17 -1 (-3250 4300)(-2550 4300);
FORCEPROP 2 LAST SIG_NAME M_L_CPU0_SA_DQS_DN<9:0>
J 0
(-3185 4310);
DISPLAY 0.489362 (-3185 4310);
WIRE 17 -1 (-3450 4025)(-3450 3925);
WIRE 17 -1 (-3450 4125)(-3450 4025);
WIRE 17 -1 (-3450 3825)(-3450 3925);
WIRE 17 -1 (-3450 3725)(-3450 3825);
WIRE 17 -1 (-3450 4225)(-3450 4125);
WIRE 17 -1 (-3450 4325)(-3450 4225);
WIRE 17 -1 (-3450 3625)(-3450 3725);
WIRE 17 -1 (-3450 3625)(-3450 3525);
WIRE 17 -1 (-3450 4350)(-3450 4325);
WIRE 17 -1 (-3450 4350)(-2550 4350);
FORCEPROP 2 LAST SIG_NAME M_L_CPU0_SA_DQS_DP<9:0>
J 0
(-3185 4360);
DISPLAY 0.489362 (-3185 4360);
WIRE 17 -1 (-3450 3175)(-3450 3075);
WIRE 17 -1 (-3450 3275)(-3450 3175);
WIRE 17 -1 (-3450 3075)(-3450 2975);
WIRE 17 -1 (-3450 2975)(-3450 2875);
WIRE 17 -1 (-3450 3300)(-3450 3275);
WIRE 17 -1 (-3450 3300)(-2550 3300);
FORCEPROP 2 LAST SIG_NAME M_L_CPU0_SB_DQS_DP<9:0>
J 0
(-3185 3310);
DISPLAY 0.489362 (-3185 3310);
WIRE 17 -1 (-3250 3125)(-3250 3025);
WIRE 17 -1 (-3250 3225)(-3250 3125);
WIRE 17 -1 (-3250 3025)(-3250 2925);
WIRE 17 -1 (-3250 2925)(-3250 2825);
WIRE 17 -1 (-3250 3250)(-3250 3225);
WIRE 17 -1 (-3250 3250)(-2550 3250);
FORCEPROP 2 LAST SIG_NAME M_L_CPU0_SB_DQS_DN<9:0>
J 0
(-3185 3260);
DISPLAY 0.489362 (-3185 3260);
WIRE 17 -1 (-3450 2775)(-3450 2875);
WIRE 17 -1 (-3450 2675)(-3450 2775);
WIRE 17 -1 (-3450 2575)(-3450 2675);
WIRE 17 -1 (-3250 3475)(-3250 3375);
WIRE 17 -1 (-3250 3575)(-3250 3475);
WIRE 17 -1 (-3450 3525)(-3450 3425);
WIRE 17 -1 (-3250 2425)(-3250 2325);
WIRE 17 -1 (-3250 2525)(-3250 2425);
WIRE 17 -1 (-3250 2525)(-3250 2625);
WIRE 17 -1 (-3250 2625)(-3250 2725);
WIRE 17 -1 (-3250 2725)(-3250 2825);
WIRE 17 -1 (-3450 2475)(-3450 2375);
WIRE 17 -1 (-3450 2575)(-3450 2475);
WIRE 16 -1 (-6450 750)(-6450 825);
WIRE 16 -1 (-8600 2725)(-8600 2800);
WIRE 16 -1 (-8350 2075)(-8350 2100);
WIRE 16 -1 (-7875 2375)(-8300 2375);
FORCEPROP 2 LAST SIG_NAME I3C_SPD_DDRGL_CPU0_SCL
J 0
(-8360 2385);
DISPLAY 0.489362 (-8360 2385);
WIRE 16 -1 (-7475 2475)(-7575 2475);
FORCEPROP 2 LAST SIG_NAME I3C_SPD_DDRL_CPU0_SCL
J 0
(-7960 2485);
DISPLAY 0.446809 (-7960 2485);
FORCEPROP 2 LASTPROP $XRERR UNIQUE?
J 0
(-8200 2485);
DISPLAY 0.638298 (-8200 2485);
PAINT MONO (-8200 2485);
DISPLAY INVISIBLE (-8200 2485);
WIRE 16 -1 (-7575 2475)(-7575 2375);
WIRE 16 -1 (-7575 2375)(-7675 2375);
WIRE 16 -1 (-7475 2525)(-8275 2525);
FORCEPROP 2 LAST SIG_NAME I3C_SPD_DDRGL_CPU0_SDA
J 0
(-8285 2535);
DISPLAY 0.489362 (-8285 2535);
WIRE 16 -1 (-7475 2575)(-8275 2575);
FORCEPROP 2 LAST SIG_NAME PD_CHL_CPU0_DIMM_SAA
J 0
(-8250 2585);
DISPLAY 0.489362 (-8250 2585);
WIRE 16 -1 (-8600 3000)(-8600 3025);
WIRE 16 -1 (-8600 3025)(-8500 3025);
WIRE 16 -1 (-8500 3050)(-8500 3025);
WIRE 16 -1 (-8500 3025)(-8500 2625);
WIRE 16 -1 (-8500 2625)(-7475 2625);
WIRE 16 -1 (-8150 1825)(-8350 1825);
WIRE 16 -1 (-8150 1825)(-8150 2225);
WIRE 16 -1 (-8350 1875)(-8350 1825);
WIRE 16 -1 (-8350 1825)(-8375 1825);
WIRE 16 -1 (-7475 2225)(-8150 2225);
FORCEPROP 2 LAST SIG_NAME PWRGD_CHL_CPU0_DIMM
J 0
(-8000 2235);
DISPLAY 0.489362 (-8000 2235);
FORCEPROP 2 LASTPROP $XRERR UNIQUE?
J 0
(-8240 2235);
DISPLAY 0.638298 (-8240 2235);
PAINT MONO (-8240 2235);
DISPLAY INVISIBLE (-8240 2235);
WIRE 16 -1 (-7475 2125)(-8075 2125);
FORCEPROP 2 LAST SIG_NAME TP_CHL_CPU0_DIMM_RFU_6
J 0
(-8085 2135);
DISPLAY 0.489362 (-8085 2135);
FORCEPROP 2 LASTPROP $XRERR UNIQUE?
J 0
(-8315 2125);
DISPLAY 0.638298 (-8315 2125);
PAINT MONO (-8315 2125);
DISPLAY INVISIBLE (-8315 2125);
WIRE 16 -1 (-7475 2725)(-8100 2725);
FORCEPROP 2 LAST SIG_NAME M_L_CPU0_ALERT_N
J 0
(-8085 2735);
DISPLAY 0.489362 (-8085 2735);
WIRE 16 -1 (-7475 2775)(-8100 2775);
FORCEPROP 2 LAST SIG_NAME M_L_CPU0_RESET_N
J 0
(-8085 2785);
DISPLAY 0.489362 (-8085 2785);
WIRE 16 -1 (-7475 1625)(-8275 1625);
FORCEPROP 2 LAST SIG_NAME M_L_CPU0_SB_RSP<0>
J 0
(-8225 1635);
DISPLAY 0.489362 (-8225 1635);
WIRE 16 -1 (-7475 1875)(-8075 1875);
FORCEPROP 2 LAST SIG_NAME TP_CHL_CPU0_DIMM_RFU_1
J 0
(-8085 1885);
DISPLAY 0.489362 (-8085 1885);
FORCEPROP 2 LASTPROP $XRERR UNIQUE?
J 0
(-8315 1875);
DISPLAY 0.638298 (-8315 1875);
PAINT MONO (-8315 1875);
DISPLAY INVISIBLE (-8315 1875);
WIRE 16 -1 (-7475 1825)(-8075 1825);
FORCEPROP 2 LAST SIG_NAME TP_CHL_CPU0_DIMM_RFU_0
J 0
(-8085 1835);
DISPLAY 0.489362 (-8085 1835);
FORCEPROP 2 LASTPROP $XRERR UNIQUE?
J 0
(-8315 1825);
DISPLAY 0.638298 (-8315 1825);
PAINT MONO (-8315 1825);
DISPLAY INVISIBLE (-8315 1825);
WIRE 16 -1 (-7475 2025)(-8075 2025);
FORCEPROP 2 LAST SIG_NAME TP_CHL_CPU0_DIMM_RFU_4
J 0
(-8085 2035);
DISPLAY 0.489362 (-8085 2035);
FORCEPROP 2 LASTPROP $XRERR UNIQUE?
J 0
(-8315 2025);
DISPLAY 0.638298 (-8315 2025);
PAINT MONO (-8315 2025);
DISPLAY INVISIBLE (-8315 2025);
WIRE 16 -1 (-7475 1975)(-8075 1975);
FORCEPROP 2 LAST SIG_NAME TP_CHL_CPU0_DIMM_RFU_3
J 0
(-8085 1985);
DISPLAY 0.489362 (-8085 1985);
FORCEPROP 2 LASTPROP $XRERR UNIQUE?
J 0
(-8315 1975);
DISPLAY 0.638298 (-8315 1975);
PAINT MONO (-8315 1975);
DISPLAY INVISIBLE (-8315 1975);
WIRE 16 -1 (-7475 1925)(-8075 1925);
FORCEPROP 2 LAST SIG_NAME TP_CHL_CPU0_DIMM_RFU_2
J 0
(-8085 1935);
DISPLAY 0.489362 (-8085 1935);
FORCEPROP 2 LASTPROP $XRERR UNIQUE?
J 0
(-8315 1925);
DISPLAY 0.638298 (-8315 1925);
PAINT MONO (-8315 1925);
DISPLAY INVISIBLE (-8315 1925);
WIRE 16 -1 (-7475 1675)(-8275 1675);
FORCEPROP 2 LAST SIG_NAME M_L_CPU0_SA_RSP<0>
J 0
(-8225 1685);
DISPLAY 0.489362 (-8225 1685);
WIRE 16 -1 (-8950 1825)(-8575 1825);
FORCEPROP 2 LAST SIG_NAME PWRGD_CHGL_CPU0
J 0
(-8935 1835);
DISPLAY 0.489362 (-8935 1835);
WIRE 16 -1 (-1900 5025)(-2200 5025);
WIRE 16 -1 (-2200 5025)(-2200 4975);
WIRE 16 -1 (-1900 4975)(-2200 4975);
WIRE 16 -1 (-2200 4975)(-2200 4925);
WIRE 16 -1 (-1900 4925)(-2200 4925);
WIRE 16 -1 (-2200 4925)(-2200 4875);
WIRE 16 -1 (-1900 4875)(-2200 4875);
WIRE 16 -1 (-2200 4875)(-2200 4825);
WIRE 16 -1 (-1900 4825)(-2200 4825);
WIRE 16 -1 (-2200 4825)(-2200 4775);
WIRE 16 -1 (-1900 4775)(-2200 4775);
WIRE 16 -1 (-2200 4775)(-2200 4725);
WIRE 16 -1 (-1900 4725)(-2200 4725);
WIRE 16 -1 (-2200 4725)(-2200 4675);
WIRE 16 -1 (-1900 4675)(-2200 4675);
WIRE 16 -1 (-2200 4675)(-2200 4625);
WIRE 16 -1 (-1900 4625)(-2200 4625);
WIRE 16 -1 (-2200 4625)(-2200 4575);
WIRE 16 -1 (-1900 4575)(-2200 4575);
WIRE 16 -1 (-2200 4575)(-2200 4525);
WIRE 16 -1 (-1900 4525)(-2200 4525);
WIRE 16 -1 (-2200 4525)(-2200 4475);
WIRE 16 -1 (-1900 4475)(-2200 4475);
WIRE 16 -1 (-2200 4475)(-2200 4425);
WIRE 16 -1 (-1900 4425)(-2200 4425);
WIRE 16 -1 (-2200 4425)(-2200 4375);
WIRE 16 -1 (-1900 4375)(-2200 4375);
WIRE 16 -1 (-2200 4375)(-2200 4325);
WIRE 16 -1 (-1900 4325)(-2200 4325);
WIRE 16 -1 (-2200 4325)(-2200 4275);
WIRE 16 -1 (-1900 4275)(-2200 4275);
WIRE 16 -1 (-2200 4275)(-2200 4225);
WIRE 16 -1 (-1900 4225)(-2200 4225);
WIRE 16 -1 (-2200 4225)(-2200 4175);
WIRE 16 -1 (-1900 4175)(-2200 4175);
WIRE 16 -1 (-2200 4175)(-2200 4125);
WIRE 16 -1 (-1900 4125)(-2200 4125);
WIRE 16 -1 (-2200 4125)(-2200 4075);
WIRE 16 -1 (-1900 4075)(-2200 4075);
WIRE 16 -1 (-2200 4075)(-2200 4025);
WIRE 16 -1 (-1900 4025)(-2200 4025);
WIRE 16 -1 (-2200 4025)(-2200 3975);
WIRE 16 -1 (-1900 3975)(-2200 3975);
WIRE 16 -1 (-2200 3975)(-2200 3925);
WIRE 16 -1 (-1900 3925)(-2200 3925);
WIRE 16 -1 (-2200 3925)(-2200 3875);
WIRE 16 -1 (-1900 3875)(-2200 3875);
WIRE 16 -1 (-2200 3875)(-2200 3825);
WIRE 16 -1 (-1900 3825)(-2200 3825);
WIRE 16 -1 (-2200 3825)(-2200 3775);
WIRE 16 -1 (-1900 3775)(-2200 3775);
WIRE 16 -1 (-2200 3775)(-2200 3725);
WIRE 16 -1 (-1900 3725)(-2200 3725);
WIRE 16 -1 (-2200 3725)(-2200 3675);
WIRE 16 -1 (-1900 3675)(-2200 3675);
WIRE 16 -1 (-2200 3675)(-2200 3625);
WIRE 16 -1 (-1900 3625)(-2200 3625);
WIRE 16 -1 (-2200 3625)(-2200 3575);
WIRE 16 -1 (-1900 3575)(-2200 3575);
WIRE 16 -1 (-2200 3575)(-2200 3525);
WIRE 16 -1 (-1900 3525)(-2200 3525);
WIRE 16 -1 (-2200 3525)(-2200 3475);
WIRE 16 -1 (-1900 3475)(-2200 3475);
WIRE 16 -1 (-2200 3475)(-2200 3425);
WIRE 16 -1 (-1900 3425)(-2200 3425);
WIRE 16 -1 (-2200 3425)(-2200 3375);
WIRE 16 -1 (-1900 3375)(-2200 3375);
WIRE 16 -1 (-2200 3375)(-2200 3325);
WIRE 16 -1 (-1900 3325)(-2200 3325);
WIRE 16 -1 (-2200 3325)(-2200 3275);
WIRE 16 -1 (-1900 3275)(-2200 3275);
WIRE 16 -1 (-2200 3275)(-2200 3225);
WIRE 16 -1 (-1900 3225)(-2200 3225);
WIRE 16 -1 (-2200 3225)(-2200 3175);
WIRE 16 -1 (-1900 3175)(-2200 3175);
WIRE 16 -1 (-2200 3175)(-2200 3125);
WIRE 16 -1 (-1900 3125)(-2200 3125);
WIRE 16 -1 (-2200 3125)(-2200 3075);
WIRE 16 -1 (-1900 3075)(-2200 3075);
WIRE 16 -1 (-2200 3075)(-2200 3025);
WIRE 16 -1 (-1900 3025)(-2200 3025);
WIRE 16 -1 (-2200 3025)(-2200 2975);
WIRE 16 -1 (-1900 2975)(-2200 2975);
WIRE 16 -1 (-2200 2975)(-2200 2925);
WIRE 16 -1 (-1900 2925)(-2200 2925);
WIRE 16 -1 (-2200 2925)(-2200 2875);
WIRE 16 -1 (-1900 2875)(-2200 2875);
WIRE 16 -1 (-2200 2875)(-2200 2825);
WIRE 16 -1 (-1900 2825)(-2200 2825);
WIRE 16 -1 (-2200 2825)(-2200 2775);
WIRE 16 -1 (-1900 2775)(-2200 2775);
WIRE 16 -1 (-2200 2775)(-2200 2725);
WIRE 16 -1 (-1900 2725)(-2200 2725);
WIRE 16 -1 (-2200 2725)(-2200 2675);
WIRE 16 -1 (-1900 2675)(-2200 2675);
WIRE 16 -1 (-2200 2675)(-2200 2625);
WIRE 16 -1 (-1900 2625)(-2200 2625);
WIRE 16 -1 (-2200 2625)(-2200 2575);
WIRE 16 -1 (-1900 2575)(-2200 2575);
WIRE 16 -1 (-2200 2575)(-2200 2525);
WIRE 16 -1 (-1900 2525)(-2200 2525);
WIRE 16 -1 (-2200 2525)(-2200 2475);
WIRE 16 -1 (-1900 2475)(-2200 2475);
WIRE 16 -1 (-2200 2475)(-2200 2425);
WIRE 16 -1 (-1900 2425)(-2200 2425);
WIRE 16 -1 (-2200 2425)(-2200 2375);
WIRE 16 -1 (-1900 2375)(-2200 2375);
WIRE 16 -1 (-2200 2375)(-2200 2325);
WIRE 16 -1 (-1900 2325)(-2200 2325);
WIRE 16 -1 (-2200 2325)(-2200 2275);
WIRE 16 -1 (-1900 2275)(-2200 2275);
WIRE 16 -1 (-2200 2275)(-2200 2225);
WIRE 16 -1 (-1900 2225)(-2200 2225);
WIRE 16 -1 (-2200 2225)(-2200 2175);
WIRE 16 -1 (-1900 2175)(-2200 2175);
WIRE 16 -1 (-2200 2175)(-2200 2125);
WIRE 16 -1 (-1900 2125)(-2200 2125);
WIRE 16 -1 (-2200 2125)(-2200 2075);
WIRE 16 -1 (-1900 2075)(-2200 2075);
WIRE 16 -1 (-2200 2075)(-2200 2025);
WIRE 16 -1 (-1900 2025)(-2200 2025);
WIRE 16 -1 (-2200 2025)(-2200 1975);
WIRE 16 -1 (-2200 1975)(-2200 1925);
WIRE 16 -1 (-1900 1975)(-2200 1975);
WIRE 16 -1 (-1900 1925)(-2200 1925);
WIRE 16 -1 (-2200 1925)(-2200 1800);
WIRE 16 -1 (-2200 5075)(-1900 5075);
WIRE 16 -1 (-2200 5125)(-2200 5075);
WIRE 16 -1 (-1900 5125)(-2200 5125);
WIRE 16 -1 (-2200 5125)(-2200 5175);
WIRE 16 -1 (-1900 5175)(-2200 5175);
WIRE 16 -1 (-2200 5175)(-2200 5800);
WIRE 16 -1 (-2325 5800)(-2200 5800);
WIRE 16 -1 (-2325 5800)(-2900 5800);
WIRE 16 -1 (-2325 5800)(-2325 5700);
WIRE 16 -1 (-2900 5800)(-2900 5875);
WIRE 16 -1 (-2900 5700)(-2900 5800);
WIRE 16 -1 (-400 5175)(-400 5125);
WIRE 16 -1 (-400 5175)(-700 5175);
WIRE 16 -1 (-400 5125)(-700 5125);
WIRE 16 -1 (-400 5125)(-400 5075);
WIRE 16 -1 (-400 5075)(-400 5025);
WIRE 16 -1 (-400 5075)(-700 5075);
WIRE 16 -1 (-400 5025)(-400 4975);
WIRE 16 -1 (-400 5025)(-700 5025);
WIRE 16 -1 (-400 4975)(-400 4925);
WIRE 16 -1 (-400 4975)(-700 4975);
WIRE 16 -1 (-400 4925)(-400 4875);
WIRE 16 -1 (-400 4925)(-700 4925);
WIRE 16 -1 (-400 4875)(-400 4825);
WIRE 16 -1 (-400 4875)(-700 4875);
WIRE 16 -1 (-400 4825)(-400 4775);
WIRE 16 -1 (-400 4825)(-700 4825);
WIRE 16 -1 (-400 4775)(-400 4725);
WIRE 16 -1 (-400 4775)(-700 4775);
WIRE 16 -1 (-400 4725)(-400 4675);
WIRE 16 -1 (-400 4725)(-700 4725);
WIRE 16 -1 (-400 4675)(-400 4625);
WIRE 16 -1 (-400 4675)(-700 4675);
WIRE 16 -1 (-400 4625)(-400 4575);
WIRE 16 -1 (-400 4625)(-700 4625);
WIRE 16 -1 (-400 4575)(-400 4525);
WIRE 16 -1 (-400 4575)(-700 4575);
WIRE 16 -1 (-400 4525)(-400 4475);
WIRE 16 -1 (-400 4525)(-700 4525);
WIRE 16 -1 (-400 4475)(-400 4425);
WIRE 16 -1 (-400 4475)(-700 4475);
WIRE 16 -1 (-400 4425)(-400 4375);
WIRE 16 -1 (-400 4425)(-700 4425);
WIRE 16 -1 (-400 4375)(-400 4325);
WIRE 16 -1 (-400 4375)(-700 4375);
WIRE 16 -1 (-400 4325)(-400 4275);
WIRE 16 -1 (-400 4325)(-700 4325);
WIRE 16 -1 (-400 4275)(-400 4225);
WIRE 16 -1 (-400 4275)(-700 4275);
WIRE 16 -1 (-400 4225)(-400 4175);
WIRE 16 -1 (-400 4225)(-700 4225);
WIRE 16 -1 (-400 4175)(-400 4125);
WIRE 16 -1 (-400 4175)(-700 4175);
WIRE 16 -1 (-400 4125)(-700 4125);
WIRE 16 -1 (-400 4125)(-400 4075);
WIRE 16 -1 (-400 4075)(-400 4025);
WIRE 16 -1 (-400 4075)(-700 4075);
WIRE 16 -1 (-400 4025)(-400 3975);
WIRE 16 -1 (-400 4025)(-700 4025);
WIRE 16 -1 (-400 3975)(-400 3925);
WIRE 16 -1 (-400 3975)(-700 3975);
WIRE 16 -1 (-400 3925)(-400 3875);
WIRE 16 -1 (-400 3925)(-700 3925);
WIRE 16 -1 (-400 3875)(-400 3825);
WIRE 16 -1 (-400 3875)(-700 3875);
WIRE 16 -1 (-400 3825)(-400 3775);
WIRE 16 -1 (-400 3825)(-700 3825);
WIRE 16 -1 (-400 3775)(-400 3725);
WIRE 16 -1 (-400 3775)(-700 3775);
WIRE 16 -1 (-400 3725)(-400 3675);
WIRE 16 -1 (-400 3725)(-700 3725);
WIRE 16 -1 (-400 3675)(-400 3625);
WIRE 16 -1 (-400 3675)(-700 3675);
WIRE 16 -1 (-400 3625)(-400 3575);
WIRE 16 -1 (-400 3625)(-700 3625);
WIRE 16 -1 (-400 3575)(-400 3525);
WIRE 16 -1 (-400 3575)(-700 3575);
WIRE 16 -1 (-400 3525)(-400 3475);
WIRE 16 -1 (-400 3525)(-700 3525);
WIRE 16 -1 (-400 3475)(-400 3425);
WIRE 16 -1 (-400 3475)(-700 3475);
WIRE 16 -1 (-400 3425)(-400 3375);
WIRE 16 -1 (-400 3425)(-700 3425);
WIRE 16 -1 (-400 3375)(-400 3325);
WIRE 16 -1 (-400 3375)(-700 3375);
WIRE 16 -1 (-400 3325)(-400 3275);
WIRE 16 -1 (-400 3325)(-700 3325);
WIRE 16 -1 (-400 3275)(-400 3225);
WIRE 16 -1 (-400 3275)(-700 3275);
WIRE 16 -1 (-400 3225)(-400 3175);
WIRE 16 -1 (-400 3225)(-700 3225);
WIRE 16 -1 (-400 3175)(-400 3125);
WIRE 16 -1 (-400 3175)(-700 3175);
WIRE 16 -1 (-400 3125)(-400 3075);
WIRE 16 -1 (-400 3125)(-700 3125);
WIRE 16 -1 (-400 3075)(-700 3075);
WIRE 16 -1 (-400 3075)(-400 3025);
WIRE 16 -1 (-400 3025)(-400 2975);
WIRE 16 -1 (-400 3025)(-700 3025);
WIRE 16 -1 (-400 2975)(-400 2925);
WIRE 16 -1 (-400 2975)(-700 2975);
WIRE 16 -1 (-400 2925)(-400 2875);
WIRE 16 -1 (-400 2925)(-700 2925);
WIRE 16 -1 (-400 2875)(-400 2825);
WIRE 16 -1 (-400 2875)(-700 2875);
WIRE 16 -1 (-400 2825)(-400 2775);
WIRE 16 -1 (-400 2825)(-700 2825);
WIRE 16 -1 (-400 2775)(-400 2725);
WIRE 16 -1 (-400 2775)(-700 2775);
WIRE 16 -1 (-400 2725)(-400 2675);
WIRE 16 -1 (-400 2725)(-700 2725);
WIRE 16 -1 (-400 2675)(-400 2625);
WIRE 16 -1 (-400 2675)(-700 2675);
WIRE 16 -1 (-400 2625)(-400 2575);
WIRE 16 -1 (-400 2625)(-700 2625);
WIRE 16 -1 (-400 2575)(-400 2525);
WIRE 16 -1 (-400 2575)(-700 2575);
WIRE 16 -1 (-400 2525)(-400 2475);
WIRE 16 -1 (-400 2525)(-700 2525);
WIRE 16 -1 (-400 2475)(-400 2425);
WIRE 16 -1 (-400 2475)(-700 2475);
WIRE 16 -1 (-400 2425)(-400 2375);
WIRE 16 -1 (-400 2425)(-700 2425);
WIRE 16 -1 (-400 2375)(-400 2325);
WIRE 16 -1 (-400 2375)(-700 2375);
WIRE 16 -1 (-400 2325)(-400 2275);
WIRE 16 -1 (-400 2325)(-700 2325);
WIRE 16 -1 (-400 2275)(-400 2225);
WIRE 16 -1 (-400 2275)(-700 2275);
WIRE 16 -1 (-400 2225)(-400 2175);
WIRE 16 -1 (-400 2225)(-700 2225);
WIRE 16 -1 (-400 2175)(-400 2125);
WIRE 16 -1 (-400 2175)(-700 2175);
WIRE 16 -1 (-400 2125)(-400 2075);
WIRE 16 -1 (-400 2125)(-700 2125);
WIRE 16 -1 (-400 2075)(-400 2025);
WIRE 16 -1 (-400 2075)(-700 2075);
WIRE 16 -1 (-400 2025)(-400 1925);
WIRE 16 -1 (-400 2025)(-700 2025);
WIRE 16 -1 (-400 1925)(-400 1875);
WIRE 16 -1 (-400 1925)(-700 1925);
WIRE 16 -1 (-400 1875)(-400 1825);
WIRE 16 -1 (-400 1875)(-700 1875);
WIRE 16 -1 (-400 1825)(-400 1575);
WIRE 16 -1 (-400 1825)(-700 1825);
WIRE 16 -1 (-3700 3250)(-3550 3250);
WIRE 16 -1 (-3700 3200)(-3350 3200);
WIRE 16 -1 (-3700 4300)(-3550 4300);
WIRE 16 -1 (-3700 4250)(-3350 4250);
WIRE 16 -1 (-3550 4200)(-3700 4200);
WIRE 16 -1 (-3700 4150)(-3350 4150);
WIRE 16 -1 (-3700 3000)(-3350 3000);
WIRE 16 -1 (-3550 4100)(-3700 4100);
WIRE 16 -1 (-3550 2950)(-3700 2950);
WIRE 16 -1 (-3700 2900)(-3350 2900);
WIRE 16 -1 (-3700 3950)(-3350 3950);
WIRE 16 -1 (-3700 2850)(-3550 2850);
WIRE 16 -1 (-3700 2800)(-3350 2800);
WIRE 16 -1 (-3700 3900)(-3550 3900);
WIRE 16 -1 (-3700 3850)(-3350 3850);
WIRE 16 -1 (-3550 2750)(-3700 2750);
WIRE 16 -1 (-3700 2700)(-3350 2700);
WIRE 16 -1 (-3550 3800)(-3700 3800);
WIRE 16 -1 (-3700 3750)(-3350 3750);
WIRE 16 -1 (-3550 2650)(-3700 2650);
WIRE 16 -1 (-3700 2600)(-3350 2600);
WIRE 16 -1 (-3550 3700)(-3700 3700);
WIRE 16 -1 (-3700 3650)(-3350 3650);
WIRE 16 -1 (-3550 2550)(-3700 2550);
WIRE 16 -1 (-3700 2500)(-3350 2500);
WIRE 16 -1 (-3550 3600)(-3700 3600);
WIRE 16 -1 (-3700 3550)(-3350 3550);
WIRE 16 -1 (-3700 2450)(-3550 2450);
WIRE 16 -1 (-3700 2400)(-3350 2400);
WIRE 16 -1 (-3700 3500)(-3550 3500);
WIRE 16 -1 (-3700 3450)(-3350 3450);
WIRE 16 -1 (-3550 2350)(-3700 2350);
WIRE 16 -1 (-3700 2300)(-3350 2300);
WIRE 16 -1 (-3550 3400)(-3700 3400);
WIRE 16 -1 (-3700 3350)(-3350 3350);
WIRE 16 -1 (-3550 3050)(-3700 3050);
WIRE 16 -1 (-3700 3100)(-3350 3100);
WIRE 16 -1 (-3550 3150)(-3700 3150);
WIRE 16 -1 (-3550 4000)(-3700 4000);
WIRE 16 -1 (-3700 4050)(-3350 4050);
WIRE 16 -1 (-6075 4425)(-6275 4425);
WIRE 16 -1 (-6075 5025)(-6275 5025);
WIRE 16 -1 (-6275 5075)(-6075 5075);
WIRE 16 -1 (-7475 2075)(-8075 2075);
FORCEPROP 2 LAST SIG_NAME TP_CHL_CPU0_DIMM_RFU_5
J 0
(-8085 2085);
DISPLAY 0.489362 (-8085 2085);
FORCEPROP 2 LASTPROP $XRERR UNIQUE?
J 0
(-8315 2075);
DISPLAY 0.638298 (-8315 2075);
PAINT MONO (-8315 2075);
DISPLAY INVISIBLE (-8315 2075);
WIRE 16 -1 (-7475 4225)(-8275 4225);
FORCEPROP 2 LAST SIG_NAME M_L_CPU0_SB_PAR
J 0
(-8225 4235);
DISPLAY 0.489362 (-8225 4235);
WIRE 16 -1 (-7475 4275)(-8275 4275);
FORCEPROP 2 LAST SIG_NAME M_L_CPU0_SA_PAR
J 0
(-8225 4285);
DISPLAY 0.489362 (-8225 4285);
WIRE 16 -1 (-6075 1875)(-6275 1875);
WIRE 16 -1 (-6075 1925)(-6275 1925);
WIRE 16 -1 (-6075 1975)(-6275 1975);
WIRE 16 -1 (-6275 2025)(-6075 2025);
WIRE 16 -1 (-6075 2075)(-6275 2075);
WIRE 16 -1 (-6075 2125)(-6275 2125);
WIRE 16 -1 (-6075 2175)(-6275 2175);
WIRE 16 -1 (-6275 2225)(-6075 2225);
WIRE 16 -1 (-6075 2275)(-6275 2275);
WIRE 16 -1 (-6075 2325)(-6275 2325);
WIRE 16 -1 (-6075 2375)(-6275 2375);
WIRE 16 -1 (-6275 2425)(-6075 2425);
WIRE 16 -1 (-6075 2475)(-6275 2475);
WIRE 16 -1 (-6075 2525)(-6275 2525);
WIRE 16 -1 (-6075 2575)(-6275 2575);
WIRE 16 -1 (-6275 2625)(-6075 2625);
WIRE 16 -1 (-6075 2675)(-6275 2675);
WIRE 16 -1 (-6075 2725)(-6275 2725);
WIRE 16 -1 (-6075 2775)(-6275 2775);
WIRE 16 -1 (-6275 2825)(-6075 2825);
WIRE 16 -1 (-6075 2875)(-6275 2875);
WIRE 16 -1 (-6075 2925)(-6275 2925);
WIRE 16 -1 (-6075 2975)(-6275 2975);
WIRE 16 -1 (-6275 3025)(-6075 3025);
WIRE 16 -1 (-6075 3075)(-6275 3075);
WIRE 16 -1 (-6075 3125)(-6275 3125);
WIRE 16 -1 (-6075 3175)(-6275 3175);
WIRE 16 -1 (-6275 3225)(-6075 3225);
WIRE 16 -1 (-6075 3275)(-6275 3275);
WIRE 16 -1 (-6075 3325)(-6275 3325);
WIRE 16 -1 (-6075 3375)(-6275 3375);
WIRE 16 -1 (-6275 3425)(-6075 3425);
WIRE 16 -1 (-6075 3525)(-6275 3525);
WIRE 16 -1 (-6075 3575)(-6275 3575);
WIRE 16 -1 (-6075 3625)(-6275 3625);
WIRE 16 -1 (-6275 3675)(-6075 3675);
WIRE 16 -1 (-6075 3725)(-6275 3725);
WIRE 16 -1 (-6075 3775)(-6275 3775);
WIRE 16 -1 (-6075 3825)(-6275 3825);
WIRE 16 -1 (-6275 3875)(-6075 3875);
WIRE 16 -1 (-6075 3925)(-6275 3925);
WIRE 16 -1 (-6075 3975)(-6275 3975);
WIRE 16 -1 (-6075 4025)(-6275 4025);
WIRE 16 -1 (-6275 4075)(-6075 4075);
WIRE 16 -1 (-6075 4125)(-6275 4125);
WIRE 16 -1 (-6075 4175)(-6275 4175);
WIRE 16 -1 (-6075 4225)(-6275 4225);
WIRE 16 -1 (-6275 4275)(-6075 4275);
WIRE 16 -1 (-6075 4325)(-6275 4325);
WIRE 16 -1 (-6075 4375)(-6275 4375);
WIRE 16 -1 (-6275 4475)(-6075 4475);
WIRE 16 -1 (-6075 4525)(-6275 4525);
WIRE 16 -1 (-6075 4575)(-6275 4575);
WIRE 16 -1 (-6075 4625)(-6275 4625);
WIRE 16 -1 (-6275 4675)(-6075 4675);
WIRE 16 -1 (-6075 4725)(-6275 4725);
WIRE 16 -1 (-6075 4775)(-6275 4775);
WIRE 16 -1 (-6075 4825)(-6275 4825);
WIRE 16 -1 (-6275 4875)(-6075 4875);
WIRE 16 -1 (-6075 4925)(-6275 4925);
WIRE 16 -1 (-6075 4975)(-6275 4975);
WIRE 16 -1 (-7475 3975)(-8275 3975);
FORCEPROP 2 LAST SIG_NAME M_L_CPU0_SB_CS_N<1>
J 0
(-8225 3985);
DISPLAY 0.489362 (-8225 3985);
WIRE 16 -1 (-7475 4125)(-8275 4125);
FORCEPROP 2 LAST SIG_NAME M_L_CPU0_SA_CS_N<1>
J 0
(-8225 4135);
DISPLAY 0.489362 (-8225 4135);
WIRE 16 -1 (-7475 3925)(-8275 3925);
FORCEPROP 2 LAST SIG_NAME M_L_CPU0_SB_CS_N<0>
J 0
(-8225 3935);
DISPLAY 0.489362 (-8225 3935);
WIRE 16 -1 (-7475 4075)(-8275 4075);
FORCEPROP 2 LAST SIG_NAME M_L_CPU0_SA_CS_N<0>
J 0
(-8225 4085);
DISPLAY 0.489362 (-8225 4085);
WIRE 16 -1 (-7475 3825)(-8275 3825);
FORCEPROP 2 LAST SIG_NAME M_L_CPU0_CLK_DP<0>
J 0
(-8225 3835);
DISPLAY 0.489362 (-8225 3835);
WIRE 16 -1 (-7475 3775)(-8275 3775);
FORCEPROP 2 LAST SIG_NAME M_L_CPU0_CLK_DN<0>
J 0
(-8225 3785);
DISPLAY 0.489362 (-8225 3785);
WIRE 16 -1 (-7475 2875)(-7675 2875);
WIRE 16 -1 (-7475 2925)(-7675 2925);
WIRE 16 -1 (-7475 2975)(-7675 2975);
WIRE 16 -1 (-7475 3025)(-7675 3025);
WIRE 16 -1 (-7475 3075)(-7675 3075);
WIRE 16 -1 (-7475 3125)(-7675 3125);
WIRE 16 -1 (-7475 3175)(-7675 3175);
WIRE 16 -1 (-7475 3325)(-7675 3325);
WIRE 16 -1 (-7475 3425)(-7675 3425);
WIRE 16 -1 (-7475 3475)(-7675 3475);
WIRE 16 -1 (-7475 3575)(-7675 3575);
WIRE 16 -1 (-7475 3625)(-7675 3625);
WIRE 16 -1 (-7475 4675)(-7675 4675);
WIRE 16 -1 (-7475 5075)(-7675 5075);
WIRE 16 -1 (-7475 4625)(-7675 4625);
WIRE 16 -1 (-7475 5025)(-7675 5025);
WIRE 16 -1 (-7475 4575)(-7675 4575);
WIRE 16 -1 (-7475 4975)(-7675 4975);
WIRE 16 -1 (-7475 4525)(-7675 4525);
WIRE 16 -1 (-7475 4925)(-7675 4925);
WIRE 16 -1 (-7475 4475)(-7675 4475);
WIRE 16 -1 (-7475 4875)(-7675 4875);
WIRE 16 -1 (-7475 4425)(-7675 4425);
WIRE 16 -1 (-7475 4825)(-7675 4825);
WIRE 16 -1 (-7475 4375)(-7675 4375);
WIRE 16 -1 (-7475 4775)(-7675 4775);
WIRE 16 -1 (-7475 3225)(-7675 3225);
WIRE 16 -1 (-7475 3375)(-7675 3375);
WIRE 16 -1 (-7475 3525)(-7675 3525);
WIRE 16 -1 (-7475 3675)(-7675 3675);
WIRE 16 -1 (-2325 5375)(-2900 5375);
WIRE 16 -1 (-2325 5375)(-2325 5500);
WIRE 16 -1 (-2900 5375)(-2900 5500);
WIRE 16 -1 (-2900 5375)(-2900 5300);
WIRE 16 -1 (-6450 1100)(-6450 1025);
WIRE 16 -1 (-6450 1100)(-7175 1100);
FORCEPROP 2 LAST SIG_NAME PD_CHL_CPU0_DIMM_SAA
J 0
(-7160 1110);
DISPLAY 0.489362 (-7160 1110);
DOT 1 (-2200 4175);
DOT 1 (-8500 3025);
DOT 1 (-2325 5800);
DOT 1 (-2900 5800);
DOT 1 (-2900 5375);
DOT 1 (-2200 5175);
DOT 1 (-400 5125);
DOT 1 (-400 5075);
DOT 1 (-400 5025);
DOT 1 (-400 4975);
DOT 1 (-400 4875);
DOT 1 (-400 4925);
DOT 1 (-400 4825);
DOT 1 (-400 4775);
DOT 1 (-400 4725);
DOT 1 (-400 4675);
DOT 1 (-400 4625);
DOT 1 (-400 4575);
DOT 1 (-400 4475);
DOT 1 (-400 4525);
DOT 1 (-400 4425);
DOT 1 (-400 4375);
DOT 1 (-400 4325);
DOT 1 (-400 4225);
DOT 1 (-400 4275);
DOT 1 (-400 4175);
DOT 1 (-400 4125);
DOT 1 (-400 4075);
DOT 1 (-400 3975);
DOT 1 (-400 4025);
DOT 1 (-400 3925);
DOT 1 (-400 3875);
DOT 1 (-400 3825);
DOT 1 (-400 3775);
DOT 1 (-400 3725);
DOT 1 (-400 3675);
DOT 1 (-400 3575);
DOT 1 (-400 3625);
DOT 1 (-2200 5125);
DOT 1 (-2200 4975);
DOT 1 (-2200 4875);
DOT 1 (-2200 4925);
DOT 1 (-2200 4825);
DOT 1 (-2200 4775);
DOT 1 (-2200 4675);
DOT 1 (-2200 4625);
DOT 1 (-2200 4575);
DOT 1 (-2200 4525);
DOT 1 (-2200 4475);
DOT 1 (-2200 4425);
DOT 1 (-2200 4375);
DOT 1 (-2200 4325);
DOT 1 (-2200 4225);
DOT 1 (-2200 4275);
DOT 1 (-2200 4125);
DOT 1 (-2200 4075);
DOT 1 (-2200 4025);
DOT 1 (-2200 3975);
DOT 1 (-2200 3925);
DOT 1 (-2200 3875);
DOT 1 (-2200 3825);
DOT 1 (-2200 3775);
DOT 1 (-2200 3725);
DOT 1 (-2200 3675);
DOT 1 (-2200 3625);
DOT 1 (-2200 3575);
DOT 1 (-400 3525);
DOT 1 (-400 3475);
DOT 1 (-400 3425);
DOT 1 (-400 3325);
DOT 1 (-400 3375);
DOT 1 (-400 3275);
DOT 1 (-400 3225);
DOT 1 (-400 3175);
DOT 1 (-400 3075);
DOT 1 (-400 3125);
DOT 1 (-400 3025);
DOT 1 (-400 2975);
DOT 1 (-400 2925);
DOT 1 (-400 2825);
DOT 1 (-400 2875);
DOT 1 (-400 2775);
DOT 1 (-400 2725);
DOT 1 (-400 2675);
DOT 1 (-400 2625);
DOT 1 (-400 2575);
DOT 1 (-400 2525);
DOT 1 (-400 2425);
DOT 1 (-400 2475);
DOT 1 (-400 2375);
DOT 1 (-400 2325);
DOT 1 (-400 2275);
DOT 1 (-400 2175);
DOT 1 (-400 2225);
DOT 1 (-400 2125);
DOT 1 (-400 2075);
DOT 1 (-400 2025);
DOT 1 (-400 1925);
DOT 1 (-400 1875);
DOT 1 (-400 1825);
DOT 1 (-2200 3525);
DOT 1 (-2200 3475);
DOT 1 (-2200 3425);
DOT 1 (-2200 3325);
DOT 1 (-2200 3375);
DOT 1 (-2200 3275);
DOT 1 (-2200 3225);
DOT 1 (-2200 3175);
DOT 1 (-2200 3075);
DOT 1 (-2200 3125);
DOT 1 (-2200 3025);
DOT 1 (-2200 2975);
DOT 1 (-2200 2925);
DOT 1 (-2200 2825);
DOT 1 (-2200 2875);
DOT 1 (-2200 2775);
DOT 1 (-2200 2725);
DOT 1 (-2200 2675);
DOT 1 (-2200 2625);
DOT 1 (-2200 2575);
DOT 1 (-2200 2525);
DOT 1 (-2200 2425);
DOT 1 (-2200 2475);
DOT 1 (-2200 2375);
DOT 1 (-2200 2325);
DOT 1 (-2200 2275);
DOT 1 (-2200 2175);
DOT 1 (-2200 2225);
DOT 1 (-2200 2125);
DOT 1 (-2200 2075);
DOT 1 (-2200 2025);
DOT 1 (-2200 1925);
DOT 1 (-2200 1975);
DOT 1 (-8350 1825);
DOT 1 (-2200 4725);
QUIT
